FILE_TYPE = MACRO_DRAWING;
SET COLOR_WIRE YELLOW;
SET COLOR_PROP MONO;
SET COLOR_DOT WHITE;
SET COLOR_ARC YELLOW;
SET COLOR_BODY GREEN;
SET COLOR_NOTE MONO;
SET PROP_DISPLAY VALUE;
SET PAGE_NUMBER P129;
FORCEADD OFFPAGE..2
(2150 5025);
FORCEPROP 2 LAST $XR0 117 
J 0
(2339 5025);
DISPLAY 0.638298 (2339 5025);
PAINT MONO (2339 5025);
FORCEPROP 2 LAST BOM_COST SB
J 0
(2475 5075);
DISPLAY 0.744681 (2475 5075);
PAINT MONO (2475 5075);
DISPLAY INVISIBLE (2475 5075);
FORCEPROP 2 LAST CDS_LIB mstr_standard
J 0
(2150 5025);
PAINT ORANGE (2150 5025);
DISPLAY INVISIBLE (2150 5025);
FORCEPROP 1 LAST OFFPAGE TRUE
J 0
(2475 4900);
DISPLAY 0.872340 (2475 4900);
PAINT GREEN (2475 4900);
DISPLAY INVISIBLE (2475 4900);
FORCEPROP 1 LAST COMMENT_BODY TRUE
J 0
(2105 4930);
DISPLAY 0.872340 (2105 4930);
PAINT PEACH (2105 4930);
DISPLAY INVISIBLE (2105 4930);
FORCEPROP 2 LAST PATH I1
J 0
(2500 5100);
DISPLAY 1.021277 (2500 5100);
PAINT ORANGE (2500 5100);
DISPLAY INVISIBLE (2500 5100);
FORCEADD OFFPAGE..2
(2150 4075);
FORCEPROP 2 LAST $XR0 29 
J 0
(2339 4075);
DISPLAY 0.638298 (2339 4075);
PAINT MONO (2339 4075);
FORCEPROP 2 LAST BOM_COST SB
J 0
(2450 4125);
DISPLAY 0.744681 (2450 4125);
PAINT MONO (2450 4125);
DISPLAY INVISIBLE (2450 4125);
FORCEPROP 2 LAST CDS_LIB mstr_standard
J 0
(2150 4075);
PAINT ORANGE (2150 4075);
DISPLAY INVISIBLE (2150 4075);
FORCEPROP 1 LAST OFFPAGE TRUE
J 0
(2475 3950);
DISPLAY 0.872340 (2475 3950);
PAINT GREEN (2475 3950);
DISPLAY INVISIBLE (2475 3950);
FORCEPROP 1 LAST COMMENT_BODY TRUE
J 0
(2105 3980);
DISPLAY 0.872340 (2105 3980);
PAINT PEACH (2105 3980);
DISPLAY INVISIBLE (2105 3980);
FORCEPROP 2 LAST PATH I10
J 0
(2450 4150);
DISPLAY 1.021277 (2450 4150);
PAINT ORANGE (2450 4150);
DISPLAY INVISIBLE (2450 4150);
FORCEADD TAP..6
R 2
(1200 3975);
FORCEPROP 3 LASTPIN (1150 3975) SIG_NAME DMI_CPU0_PCH_RX_C_DN<3>
J 0
(1160 3985);
DISPLAY 0.659574 (1160 3985);
PAINT MONO (1160 3985);
DISPLAY INVISIBLE (1160 3985);
FORCEPROP 1 LASTPIN (1150 3975) BN 3
J 2
(1202 3983);
DISPLAY 0.617021 (1202 3983);
PAINT VIOLET (1202 3983);
FORCEPROP 2 LAST BOM_COST SB
J 0
(1175 4025);
DISPLAY 0.744681 (1175 4025);
PAINT MONO (1175 4025);
DISPLAY INVISIBLE (1175 4025);
FORCEPROP 2 LAST CDS_LIB mstr_standard
J 0
(1200 3975);
PAINT ORANGE (1200 3975);
DISPLAY INVISIBLE (1200 3975);
FORCEPROP 1 LAST BODY_TYPE PLUMBING
J 2
(1200 3925);
DISPLAY 0.872340 (1200 3925);
PAINT GREEN (1200 3925);
DISPLAY INVISIBLE (1200 3925);
FORCEPROP 1 LAST HDL_TAP TRUE
J 2
(875 3850);
DISPLAY 0.872340 (875 3850);
PAINT ORANGE (875 3850);
DISPLAY INVISIBLE (875 3850);
FORCEPROP 1 LAST PATH I11
J 2
(1202 3975);
DISPLAY 0.872340 (1202 3975);
PAINT GREEN (1202 3975);
DISPLAY INVISIBLE (1202 3975);
FORCEADD TAP..6
R 2
(1200 3775);
FORCEPROP 3 LASTPIN (1150 3775) SIG_NAME DMI_CPU0_PCH_RX_C_DN<2>
J 0
(1160 3785);
DISPLAY 0.659574 (1160 3785);
PAINT MONO (1160 3785);
DISPLAY INVISIBLE (1160 3785);
FORCEPROP 1 LASTPIN (1150 3775) BN 2
J 2
(1202 3783);
DISPLAY 0.617021 (1202 3783);
PAINT VIOLET (1202 3783);
FORCEPROP 2 LAST BOM_COST SB
J 0
(1175 3825);
DISPLAY 0.744681 (1175 3825);
PAINT MONO (1175 3825);
DISPLAY INVISIBLE (1175 3825);
FORCEPROP 2 LAST CDS_LIB mstr_standard
J 0
(1200 3775);
PAINT ORANGE (1200 3775);
DISPLAY INVISIBLE (1200 3775);
FORCEPROP 1 LAST BODY_TYPE PLUMBING
J 2
(1200 3725);
DISPLAY 0.872340 (1200 3725);
PAINT GREEN (1200 3725);
DISPLAY INVISIBLE (1200 3725);
FORCEPROP 1 LAST HDL_TAP TRUE
J 2
(875 3650);
DISPLAY 0.872340 (875 3650);
PAINT ORANGE (875 3650);
DISPLAY INVISIBLE (875 3650);
FORCEPROP 1 LAST PATH I12
J 2
(1202 3775);
DISPLAY 0.872340 (1202 3775);
PAINT GREEN (1202 3775);
DISPLAY INVISIBLE (1202 3775);
FORCEADD TAP..6
R 2
(1200 3375);
FORCEPROP 3 LASTPIN (1150 3375) SIG_NAME DMI_CPU0_PCH_RX_C_DN<0>
J 0
(1160 3385);
DISPLAY 0.659574 (1160 3385);
PAINT MONO (1160 3385);
DISPLAY INVISIBLE (1160 3385);
FORCEPROP 1 LASTPIN (1150 3375) BN 0
J 2
(1202 3383);
DISPLAY 0.617021 (1202 3383);
PAINT VIOLET (1202 3383);
FORCEPROP 2 LAST BOM_COST SB
J 0
(1175 3425);
DISPLAY 0.744681 (1175 3425);
PAINT MONO (1175 3425);
DISPLAY INVISIBLE (1175 3425);
FORCEPROP 2 LAST CDS_LIB mstr_standard
J 0
(1200 3375);
PAINT ORANGE (1200 3375);
DISPLAY INVISIBLE (1200 3375);
FORCEPROP 1 LAST BODY_TYPE PLUMBING
J 2
(1200 3325);
DISPLAY 0.872340 (1200 3325);
PAINT GREEN (1200 3325);
DISPLAY INVISIBLE (1200 3325);
FORCEPROP 1 LAST HDL_TAP TRUE
J 2
(875 3250);
DISPLAY 0.872340 (875 3250);
PAINT ORANGE (875 3250);
DISPLAY INVISIBLE (875 3250);
FORCEPROP 1 LAST PATH I13
J 2
(1202 3375);
DISPLAY 0.872340 (1202 3375);
PAINT GREEN (1202 3375);
DISPLAY INVISIBLE (1202 3375);
FORCEADD TAP..6
R 2
(1200 3575);
FORCEPROP 3 LASTPIN (1150 3575) SIG_NAME DMI_CPU0_PCH_RX_C_DN<1>
J 0
(1160 3585);
DISPLAY 0.659574 (1160 3585);
PAINT MONO (1160 3585);
DISPLAY INVISIBLE (1160 3585);
FORCEPROP 1 LASTPIN (1150 3575) BN 1
J 2
(1202 3583);
DISPLAY 0.617021 (1202 3583);
PAINT VIOLET (1202 3583);
FORCEPROP 2 LAST BOM_COST SB
J 0
(1175 3625);
DISPLAY 0.744681 (1175 3625);
PAINT MONO (1175 3625);
DISPLAY INVISIBLE (1175 3625);
FORCEPROP 2 LAST CDS_LIB mstr_standard
J 0
(1200 3575);
PAINT ORANGE (1200 3575);
DISPLAY INVISIBLE (1200 3575);
FORCEPROP 1 LAST BODY_TYPE PLUMBING
J 2
(1200 3525);
DISPLAY 0.872340 (1200 3525);
PAINT GREEN (1200 3525);
DISPLAY INVISIBLE (1200 3525);
FORCEPROP 1 LAST HDL_TAP TRUE
J 2
(875 3450);
DISPLAY 0.872340 (875 3450);
PAINT ORANGE (875 3450);
DISPLAY INVISIBLE (875 3450);
FORCEPROP 1 LAST PATH I14
J 2
(1202 3575);
DISPLAY 0.872340 (1202 3575);
PAINT GREEN (1202 3575);
DISPLAY INVISIBLE (1202 3575);
FORCEADD TAP..6
R 2
(1200 4925);
FORCEPROP 3 LASTPIN (1150 4925) SIG_NAME DMI_CPU0_PCH_TX_C_DN<3>
J 0
(1160 4935);
DISPLAY 0.659574 (1160 4935);
PAINT MONO (1160 4935);
DISPLAY INVISIBLE (1160 4935);
FORCEPROP 1 LASTPIN (1150 4925) BN 3
J 2
(1202 4933);
DISPLAY 0.617021 (1202 4933);
PAINT VIOLET (1202 4933);
FORCEPROP 2 LAST BOM_COST SB
J 0
(1175 4975);
DISPLAY 0.744681 (1175 4975);
PAINT MONO (1175 4975);
DISPLAY INVISIBLE (1175 4975);
FORCEPROP 2 LAST CDS_LIB mstr_standard
J 0
(1200 4925);
PAINT ORANGE (1200 4925);
DISPLAY INVISIBLE (1200 4925);
FORCEPROP 1 LAST BODY_TYPE PLUMBING
J 2
(1200 4875);
DISPLAY 0.872340 (1200 4875);
PAINT GREEN (1200 4875);
DISPLAY INVISIBLE (1200 4875);
FORCEPROP 1 LAST HDL_TAP TRUE
J 2
(875 4800);
DISPLAY 0.872340 (875 4800);
PAINT GREEN (875 4800);
DISPLAY INVISIBLE (875 4800);
FORCEPROP 1 LAST PATH I2
J 2
(1202 4925);
DISPLAY 0.872340 (1202 4925);
PAINT GREEN (1202 4925);
DISPLAY INVISIBLE (1202 4925);
FORCEADD TAP..1
R 2
(-125 4925);
FORCEPROP 3 LASTPIN (-75 4925) SIG_NAME DMI_CPU0_PCH_TX_DN<3>
J 0
(-65 4935);
DISPLAY 0.659574 (-65 4935);
PAINT MONO (-65 4935);
DISPLAY INVISIBLE (-65 4935);
FORCEPROP 1 LASTPIN (-75 4925) BN 3
J 2
(-63 4933);
DISPLAY 0.617021 (-63 4933);
PAINT VIOLET (-63 4933);
FORCEPROP 2 LAST BOM_COST SB
J 0
(-150 4975);
DISPLAY 0.744681 (-150 4975);
PAINT MONO (-150 4975);
DISPLAY INVISIBLE (-150 4975);
FORCEPROP 2 LAST CDS_LIB mstr_standard
J 0
(-125 4925);
PAINT ORANGE (-125 4925);
DISPLAY INVISIBLE (-125 4925);
FORCEPROP 1 LAST BODY_TYPE PLUMBING
J 2
(-125 4975);
DISPLAY 1.085106 (-125 4975);
PAINT GREEN (-125 4975);
DISPLAY INVISIBLE (-125 4975);
FORCEPROP 1 LAST HDL_TAP TRUE
J 2
(-450 4800);
DISPLAY 1.085106 (-450 4800);
PAINT GREEN (-450 4800);
DISPLAY INVISIBLE (-450 4800);
FORCEPROP 1 LAST PATH I23
J 2
(-123 4925);
DISPLAY 0.872340 (-123 4925);
PAINT GREEN (-123 4925);
DISPLAY INVISIBLE (-123 4925);
FORCEADD TAP..1
R 2
(-125 4725);
FORCEPROP 3 LASTPIN (-75 4725) SIG_NAME DMI_CPU0_PCH_TX_DN<2>
J 0
(-65 4735);
DISPLAY 0.659574 (-65 4735);
PAINT MONO (-65 4735);
DISPLAY INVISIBLE (-65 4735);
FORCEPROP 1 LASTPIN (-75 4725) BN 2
J 2
(-63 4733);
DISPLAY 0.617021 (-63 4733);
PAINT VIOLET (-63 4733);
FORCEPROP 2 LAST BOM_COST SB
J 0
(-150 4775);
DISPLAY 0.744681 (-150 4775);
PAINT MONO (-150 4775);
DISPLAY INVISIBLE (-150 4775);
FORCEPROP 2 LAST CDS_LIB mstr_standard
J 0
(-125 4725);
PAINT ORANGE (-125 4725);
DISPLAY INVISIBLE (-125 4725);
FORCEPROP 1 LAST BODY_TYPE PLUMBING
J 2
(-125 4775);
DISPLAY 1.085106 (-125 4775);
PAINT GREEN (-125 4775);
DISPLAY INVISIBLE (-125 4775);
FORCEPROP 1 LAST HDL_TAP TRUE
J 2
(-450 4600);
DISPLAY 1.085106 (-450 4600);
PAINT GREEN (-450 4600);
DISPLAY INVISIBLE (-450 4600);
FORCEPROP 1 LAST PATH I24
J 2
(-123 4725);
DISPLAY 0.872340 (-123 4725);
PAINT GREEN (-123 4725);
DISPLAY INVISIBLE (-123 4725);
FORCEADD TAP..1
R 2
(-125 4525);
FORCEPROP 3 LASTPIN (-75 4525) SIG_NAME DMI_CPU0_PCH_TX_DN<1>
J 0
(-65 4535);
DISPLAY 0.659574 (-65 4535);
PAINT MONO (-65 4535);
DISPLAY INVISIBLE (-65 4535);
FORCEPROP 1 LASTPIN (-75 4525) BN 1
J 2
(-63 4533);
DISPLAY 0.617021 (-63 4533);
PAINT VIOLET (-63 4533);
FORCEPROP 2 LAST BOM_COST SB
J 0
(-150 4575);
DISPLAY 0.744681 (-150 4575);
PAINT MONO (-150 4575);
DISPLAY INVISIBLE (-150 4575);
FORCEPROP 2 LAST CDS_LIB mstr_standard
J 0
(-125 4525);
PAINT ORANGE (-125 4525);
DISPLAY INVISIBLE (-125 4525);
FORCEPROP 1 LAST BODY_TYPE PLUMBING
J 2
(-125 4575);
DISPLAY 1.085106 (-125 4575);
PAINT GREEN (-125 4575);
DISPLAY INVISIBLE (-125 4575);
FORCEPROP 1 LAST HDL_TAP TRUE
J 2
(-450 4400);
DISPLAY 1.085106 (-450 4400);
PAINT GREEN (-450 4400);
DISPLAY INVISIBLE (-450 4400);
FORCEPROP 1 LAST PATH I25
J 2
(-123 4525);
DISPLAY 0.872340 (-123 4525);
PAINT GREEN (-123 4525);
DISPLAY INVISIBLE (-123 4525);
FORCEADD TAP..1
R 2
(-125 4325);
FORCEPROP 3 LASTPIN (-75 4325) SIG_NAME DMI_CPU0_PCH_TX_DN<0>
J 0
(-65 4335);
DISPLAY 0.659574 (-65 4335);
PAINT MONO (-65 4335);
DISPLAY INVISIBLE (-65 4335);
FORCEPROP 1 LASTPIN (-75 4325) BN 0
J 2
(-63 4333);
DISPLAY 0.617021 (-63 4333);
PAINT VIOLET (-63 4333);
FORCEPROP 2 LAST BOM_COST SB
J 0
(-150 4375);
DISPLAY 0.744681 (-150 4375);
PAINT MONO (-150 4375);
DISPLAY INVISIBLE (-150 4375);
FORCEPROP 2 LAST CDS_LIB mstr_standard
J 0
(-125 4325);
PAINT ORANGE (-125 4325);
DISPLAY INVISIBLE (-125 4325);
FORCEPROP 1 LAST BODY_TYPE PLUMBING
J 2
(-125 4375);
DISPLAY 1.085106 (-125 4375);
PAINT GREEN (-125 4375);
DISPLAY INVISIBLE (-125 4375);
FORCEPROP 1 LAST HDL_TAP TRUE
J 2
(-450 4200);
DISPLAY 1.085106 (-450 4200);
PAINT GREEN (-450 4200);
DISPLAY INVISIBLE (-450 4200);
FORCEPROP 1 LAST PATH I26
J 2
(-123 4325);
DISPLAY 0.872340 (-123 4325);
PAINT GREEN (-123 4325);
DISPLAY INVISIBLE (-123 4325);
FORCEADD OFFPAGE..1
(-1000 5025);
FORCEPROP 2 LAST $XR0 29 
J 0
(-1251 5025);
DISPLAY 0.638298 (-1251 5025);
PAINT MONO (-1251 5025);
FORCEPROP 2 LAST BOM_COST SB
J 0
(-1250 5075);
DISPLAY 0.744681 (-1250 5075);
PAINT MONO (-1250 5075);
DISPLAY INVISIBLE (-1250 5075);
FORCEPROP 2 LAST CDS_LIB mstr_standard
J 0
(-1000 5025);
PAINT ORANGE (-1000 5025);
DISPLAY INVISIBLE (-1000 5025);
FORCEPROP 1 LAST OFFPAGE TRUE
J 0
(-675 4900);
DISPLAY 1.085106 (-675 4900);
PAINT GREEN (-675 4900);
DISPLAY INVISIBLE (-675 4900);
FORCEPROP 1 LAST COMMENT_BODY TRUE
J 0
(-875 4925);
DISPLAY 1.085106 (-875 4925);
PAINT PEACH (-875 4925);
DISPLAY INVISIBLE (-875 4925);
FORCEPROP 2 LAST PATH I27
J 0
(-1250 5100);
DISPLAY 1.021277 (-1250 5100);
PAINT ORANGE (-1250 5100);
DISPLAY INVISIBLE (-1250 5100);
FORCEADD OFFPAGE..2
(-1900 5025);
FORCEPROP 2 LAST $XR0 117 
J 0
(-1711 5025);
DISPLAY 0.638298 (-1711 5025);
PAINT MONO (-1711 5025);
FORCEPROP 2 LAST BOM_COST SB
J 0
(-1575 5075);
DISPLAY 0.744681 (-1575 5075);
PAINT MONO (-1575 5075);
DISPLAY INVISIBLE (-1575 5075);
FORCEPROP 2 LAST CDS_LIB mstr_standard
J 0
(-1900 5025);
PAINT ORANGE (-1900 5025);
DISPLAY INVISIBLE (-1900 5025);
FORCEPROP 1 LAST OFFPAGE TRUE
J 0
(-1575 4900);
DISPLAY 0.872340 (-1575 4900);
PAINT GREEN (-1575 4900);
DISPLAY INVISIBLE (-1575 4900);
FORCEPROP 1 LAST COMMENT_BODY TRUE
J 0
(-1945 4930);
DISPLAY 0.872340 (-1945 4930);
PAINT PEACH (-1945 4930);
DISPLAY INVISIBLE (-1945 4930);
FORCEPROP 2 LAST PATH I28
J 0
(-1550 5100);
DISPLAY 1.021277 (-1550 5100);
PAINT ORANGE (-1550 5100);
DISPLAY INVISIBLE (-1550 5100);
FORCEADD TAP..6
R 2
(-2800 4925);
FORCEPROP 3 LASTPIN (-2850 4925) SIG_NAME DMI_CPU0_PCH_TX_C_DP<3>
J 0
(-2840 4935);
DISPLAY 0.659574 (-2840 4935);
PAINT MONO (-2840 4935);
DISPLAY INVISIBLE (-2840 4935);
FORCEPROP 1 LASTPIN (-2850 4925) BN 3
J 2
(-2798 4933);
DISPLAY 0.617021 (-2798 4933);
PAINT VIOLET (-2798 4933);
FORCEPROP 2 LAST BOM_COST SB
J 0
(-2825 4975);
DISPLAY 0.744681 (-2825 4975);
PAINT MONO (-2825 4975);
DISPLAY INVISIBLE (-2825 4975);
FORCEPROP 2 LAST CDS_LIB mstr_standard
J 0
(-2800 4925);
PAINT ORANGE (-2800 4925);
DISPLAY INVISIBLE (-2800 4925);
FORCEPROP 1 LAST BODY_TYPE PLUMBING
J 2
(-2800 4875);
DISPLAY 0.872340 (-2800 4875);
PAINT GREEN (-2800 4875);
DISPLAY INVISIBLE (-2800 4875);
FORCEPROP 1 LAST HDL_TAP TRUE
J 2
(-3125 4800);
DISPLAY 0.872340 (-3125 4800);
PAINT GREEN (-3125 4800);
DISPLAY INVISIBLE (-3125 4800);
FORCEPROP 1 LAST PATH I29
J 2
(-2798 4925);
DISPLAY 0.872340 (-2798 4925);
PAINT GREEN (-2798 4925);
DISPLAY INVISIBLE (-2798 4925);
FORCEADD TAP..6
R 2
(1200 4725);
FORCEPROP 3 LASTPIN (1150 4725) SIG_NAME DMI_CPU0_PCH_TX_C_DN<2>
J 0
(1160 4735);
DISPLAY 0.659574 (1160 4735);
PAINT MONO (1160 4735);
DISPLAY INVISIBLE (1160 4735);
FORCEPROP 1 LASTPIN (1150 4725) BN 2
J 2
(1202 4733);
DISPLAY 0.617021 (1202 4733);
PAINT VIOLET (1202 4733);
FORCEPROP 2 LAST BOM_COST SB
J 0
(1175 4775);
DISPLAY 0.744681 (1175 4775);
PAINT MONO (1175 4775);
DISPLAY INVISIBLE (1175 4775);
FORCEPROP 2 LAST CDS_LIB mstr_standard
J 0
(1200 4725);
PAINT ORANGE (1200 4725);
DISPLAY INVISIBLE (1200 4725);
FORCEPROP 1 LAST BODY_TYPE PLUMBING
J 2
(1200 4675);
DISPLAY 0.872340 (1200 4675);
PAINT GREEN (1200 4675);
DISPLAY INVISIBLE (1200 4675);
FORCEPROP 1 LAST HDL_TAP TRUE
J 2
(875 4600);
DISPLAY 0.872340 (875 4600);
PAINT GREEN (875 4600);
DISPLAY INVISIBLE (875 4600);
FORCEPROP 1 LAST PATH I3
J 2
(1202 4725);
DISPLAY 0.872340 (1202 4725);
PAINT GREEN (1202 4725);
DISPLAY INVISIBLE (1202 4725);
FORCEADD TAP..6
R 2
(-2800 4725);
FORCEPROP 3 LASTPIN (-2850 4725) SIG_NAME DMI_CPU0_PCH_TX_C_DP<2>
J 0
(-2840 4735);
DISPLAY 0.659574 (-2840 4735);
PAINT MONO (-2840 4735);
DISPLAY INVISIBLE (-2840 4735);
FORCEPROP 1 LASTPIN (-2850 4725) BN 2
J 2
(-2798 4733);
DISPLAY 0.617021 (-2798 4733);
PAINT VIOLET (-2798 4733);
FORCEPROP 2 LAST BOM_COST SB
J 0
(-2825 4775);
DISPLAY 0.744681 (-2825 4775);
PAINT MONO (-2825 4775);
DISPLAY INVISIBLE (-2825 4775);
FORCEPROP 2 LAST CDS_LIB mstr_standard
J 0
(-2800 4725);
PAINT ORANGE (-2800 4725);
DISPLAY INVISIBLE (-2800 4725);
FORCEPROP 1 LAST BODY_TYPE PLUMBING
J 2
(-2800 4675);
DISPLAY 0.872340 (-2800 4675);
PAINT GREEN (-2800 4675);
DISPLAY INVISIBLE (-2800 4675);
FORCEPROP 1 LAST HDL_TAP TRUE
J 2
(-3125 4600);
DISPLAY 0.872340 (-3125 4600);
PAINT GREEN (-3125 4600);
DISPLAY INVISIBLE (-3125 4600);
FORCEPROP 1 LAST PATH I30
J 2
(-2798 4725);
DISPLAY 0.872340 (-2798 4725);
PAINT GREEN (-2798 4725);
DISPLAY INVISIBLE (-2798 4725);
FORCEADD TAP..6
R 2
(-2800 4525);
FORCEPROP 3 LASTPIN (-2850 4525) SIG_NAME DMI_CPU0_PCH_TX_C_DP<1>
J 0
(-2840 4535);
DISPLAY 0.659574 (-2840 4535);
PAINT MONO (-2840 4535);
DISPLAY INVISIBLE (-2840 4535);
FORCEPROP 1 LASTPIN (-2850 4525) BN 1
J 2
(-2798 4533);
DISPLAY 0.617021 (-2798 4533);
PAINT VIOLET (-2798 4533);
FORCEPROP 2 LAST BOM_COST SB
J 0
(-2825 4575);
DISPLAY 0.744681 (-2825 4575);
PAINT MONO (-2825 4575);
DISPLAY INVISIBLE (-2825 4575);
FORCEPROP 2 LAST CDS_LIB mstr_standard
J 0
(-2800 4525);
PAINT ORANGE (-2800 4525);
DISPLAY INVISIBLE (-2800 4525);
FORCEPROP 1 LAST BODY_TYPE PLUMBING
J 2
(-2800 4475);
DISPLAY 0.872340 (-2800 4475);
PAINT GREEN (-2800 4475);
DISPLAY INVISIBLE (-2800 4475);
FORCEPROP 1 LAST HDL_TAP TRUE
J 2
(-3125 4400);
DISPLAY 0.872340 (-3125 4400);
PAINT GREEN (-3125 4400);
DISPLAY INVISIBLE (-3125 4400);
FORCEPROP 1 LAST PATH I31
J 2
(-2798 4525);
DISPLAY 0.872340 (-2798 4525);
PAINT GREEN (-2798 4525);
DISPLAY INVISIBLE (-2798 4525);
FORCEADD TAP..6
R 2
(-2800 4325);
FORCEPROP 3 LASTPIN (-2850 4325) SIG_NAME DMI_CPU0_PCH_TX_C_DP<0>
J 0
(-2840 4335);
DISPLAY 0.659574 (-2840 4335);
PAINT MONO (-2840 4335);
DISPLAY INVISIBLE (-2840 4335);
FORCEPROP 1 LASTPIN (-2850 4325) BN 0
J 2
(-2798 4333);
DISPLAY 0.617021 (-2798 4333);
PAINT VIOLET (-2798 4333);
FORCEPROP 2 LAST BOM_COST SB
J 0
(-2825 4375);
DISPLAY 0.744681 (-2825 4375);
PAINT MONO (-2825 4375);
DISPLAY INVISIBLE (-2825 4375);
FORCEPROP 2 LAST CDS_LIB mstr_standard
J 0
(-2800 4325);
PAINT ORANGE (-2800 4325);
DISPLAY INVISIBLE (-2800 4325);
FORCEPROP 1 LAST BODY_TYPE PLUMBING
J 2
(-2800 4275);
DISPLAY 0.872340 (-2800 4275);
PAINT GREEN (-2800 4275);
DISPLAY INVISIBLE (-2800 4275);
FORCEPROP 1 LAST HDL_TAP TRUE
J 2
(-3125 4200);
DISPLAY 0.872340 (-3125 4200);
PAINT GREEN (-3125 4200);
DISPLAY INVISIBLE (-3125 4200);
FORCEPROP 1 LAST PATH I32
J 2
(-2798 4325);
DISPLAY 0.872340 (-2798 4325);
PAINT GREEN (-2798 4325);
DISPLAY INVISIBLE (-2798 4325);
FORCEADD CAP..1
R 1
(-3650 4925);
FORCEPROP 1 LAST LOCATION C7B25
J 0
(-3725 5025);
DISPLAY 0.617021 (-3725 5025);
PAINT AQUA (-3725 5025);
FORCEPROP 1 LAST VALUE 0.22UF
J 0
(-3850 4875);
DISPLAY 0.617021 (-3850 4875);
PAINT SKYBLUE (-3850 4875);
FORCEPROP 1 LAST TOLERANCE 10%
J 0
(-3825 4825);
DISPLAY 0.617021 (-3825 4825);
PAINT SKYBLUE (-3825 4825);
FORCEPROP 1 LAST PACK_TYPE 0402
J 0
(-3825 4775);
DISPLAY 0.617021 (-3825 4775);
PAINT SKYBLUE (-3825 4775);
FORCEPROP 1 LASTPIN (-3550 4925) $PN 2
J 0
(-3580 4935);
DISPLAY 0.617021 (-3580 4935);
PAINT WHITE (-3580 4935);
FORCEPROP 1 LASTPIN (-3750 4925) $PN 1
J 0
(-3755 4935);
DISPLAY 0.617021 (-3755 4935);
PAINT WHITE (-3755 4935);
FORCEPROP 1 LAST MATERIAL X7R
J 0
(-3600 4825);
DISPLAY 0.617021 (-3600 4825);
PAINT SKYBLUE (-3600 4825);
FORCEPROP 1 LAST VOLTAGE 16V
J 0
(-3600 4875);
DISPLAY 0.638298 (-3600 4875);
PAINT SKYBLUE (-3600 4875);
FORCEPROP 1 LAST PART_NUMBER A36096-155
J 0
(-3800 4975);
DISPLAY 0.617021 (-3800 4975);
PAINT BLUE (-3800 4975);
FORCEPROP 2 LAST BOM_COST SB
J 0
(-3725 5075);
DISPLAY 0.744681 (-3725 5075);
PAINT MONO (-3725 5075);
DISPLAY INVISIBLE (-3725 5075);
FORCEPROP 2 LAST CDS_LIB mstr_discrete
J 0
(-3650 4925);
PAINT ORANGE (-3650 4925);
DISPLAY INVISIBLE (-3650 4925);
FORCEPROP 2 LAST CDS_SEC 1
J 0
(-3525 5225);
PAINT MONO (-3525 5225);
DISPLAY INVISIBLE (-3525 5225);
FORCEPROP 2 LAST $SEC 1
J 0
(-3525 5225);
PAINT MONO (-3525 5225);
DISPLAY INVISIBLE (-3525 5225);
FORCEPROP 2 LAST CDS_LOCATION C7B25
J 0
(-3725 5025);
DISPLAY 0.617021 (-3725 5025);
PAINT AQUA (-3725 5025);
DISPLAY INVISIBLE (-3725 5025);
FORCEPROP 1 LAST PATH I35
R 1
J 0
(-3800 4975);
DISPLAY 0.978723 (-3800 4975);
PAINT WHITE (-3800 4975);
DISPLAY INVISIBLE (-3800 4975);
FORCEPROP 2 LAST ROOM DMI
J 0
(-3525 5225);
PAINT ORANGE (-3525 5225);
DISPLAY INVISIBLE (-3525 5225);
FORCEADD TAP..1
R 2
(-150 3975);
FORCEPROP 3 LASTPIN (-100 3975) SIG_NAME DMI_CPU0_PCH_RX_DN<3>
J 0
(-90 3985);
DISPLAY 0.659574 (-90 3985);
PAINT MONO (-90 3985);
DISPLAY INVISIBLE (-90 3985);
FORCEPROP 1 LASTPIN (-100 3975) BN 3
J 2
(-88 3983);
DISPLAY 0.617021 (-88 3983);
PAINT VIOLET (-88 3983);
FORCEPROP 2 LAST BOM_COST SB
J 0
(-175 4025);
DISPLAY 0.744681 (-175 4025);
PAINT MONO (-175 4025);
DISPLAY INVISIBLE (-175 4025);
FORCEPROP 2 LAST CDS_LIB mstr_standard
J 0
(-150 3975);
PAINT ORANGE (-150 3975);
DISPLAY INVISIBLE (-150 3975);
FORCEPROP 1 LAST BODY_TYPE PLUMBING
J 2
(-150 4025);
DISPLAY 1.085106 (-150 4025);
PAINT GREEN (-150 4025);
DISPLAY INVISIBLE (-150 4025);
FORCEPROP 1 LAST HDL_TAP TRUE
J 2
(-475 3850);
DISPLAY 1.085106 (-475 3850);
PAINT GREEN (-475 3850);
DISPLAY INVISIBLE (-475 3850);
FORCEPROP 1 LAST PATH I37
J 2
(-148 3975);
DISPLAY 0.872340 (-148 3975);
PAINT GREEN (-148 3975);
DISPLAY INVISIBLE (-148 3975);
FORCEADD TAP..1
R 2
(-150 3775);
FORCEPROP 3 LASTPIN (-100 3775) SIG_NAME DMI_CPU0_PCH_RX_DN<2>
J 0
(-90 3785);
DISPLAY 0.659574 (-90 3785);
PAINT MONO (-90 3785);
DISPLAY INVISIBLE (-90 3785);
FORCEPROP 1 LASTPIN (-100 3775) BN 2
J 2
(-88 3783);
DISPLAY 0.617021 (-88 3783);
PAINT VIOLET (-88 3783);
FORCEPROP 2 LAST BOM_COST SB
J 0
(-175 3825);
DISPLAY 0.744681 (-175 3825);
PAINT MONO (-175 3825);
DISPLAY INVISIBLE (-175 3825);
FORCEPROP 2 LAST CDS_LIB mstr_standard
J 0
(-150 3775);
PAINT ORANGE (-150 3775);
DISPLAY INVISIBLE (-150 3775);
FORCEPROP 1 LAST BODY_TYPE PLUMBING
J 2
(-150 3825);
DISPLAY 1.085106 (-150 3825);
PAINT GREEN (-150 3825);
DISPLAY INVISIBLE (-150 3825);
FORCEPROP 1 LAST HDL_TAP TRUE
J 2
(-475 3650);
DISPLAY 1.085106 (-475 3650);
PAINT GREEN (-475 3650);
DISPLAY INVISIBLE (-475 3650);
FORCEPROP 1 LAST PATH I38
J 2
(-148 3775);
DISPLAY 0.872340 (-148 3775);
PAINT GREEN (-148 3775);
DISPLAY INVISIBLE (-148 3775);
FORCEADD TAP..1
R 2
(-150 3375);
FORCEPROP 3 LASTPIN (-100 3375) SIG_NAME DMI_CPU0_PCH_RX_DN<0>
J 0
(-90 3385);
DISPLAY 0.659574 (-90 3385);
PAINT MONO (-90 3385);
DISPLAY INVISIBLE (-90 3385);
FORCEPROP 1 LASTPIN (-100 3375) BN 0
J 2
(-88 3383);
DISPLAY 0.617021 (-88 3383);
PAINT VIOLET (-88 3383);
FORCEPROP 2 LAST BOM_COST SB
J 0
(-175 3425);
DISPLAY 0.744681 (-175 3425);
PAINT MONO (-175 3425);
DISPLAY INVISIBLE (-175 3425);
FORCEPROP 2 LAST CDS_LIB mstr_standard
J 0
(-150 3375);
PAINT ORANGE (-150 3375);
DISPLAY INVISIBLE (-150 3375);
FORCEPROP 1 LAST BODY_TYPE PLUMBING
J 2
(-150 3425);
DISPLAY 1.085106 (-150 3425);
PAINT GREEN (-150 3425);
DISPLAY INVISIBLE (-150 3425);
FORCEPROP 1 LAST HDL_TAP TRUE
J 2
(-475 3250);
DISPLAY 1.085106 (-475 3250);
PAINT GREEN (-475 3250);
DISPLAY INVISIBLE (-475 3250);
FORCEPROP 1 LAST PATH I39
J 2
(-148 3375);
DISPLAY 0.872340 (-148 3375);
PAINT GREEN (-148 3375);
DISPLAY INVISIBLE (-148 3375);
FORCEADD TAP..6
R 2
(1200 4525);
FORCEPROP 3 LASTPIN (1150 4525) SIG_NAME DMI_CPU0_PCH_TX_C_DN<1>
J 0
(1160 4535);
DISPLAY 0.659574 (1160 4535);
PAINT MONO (1160 4535);
DISPLAY INVISIBLE (1160 4535);
FORCEPROP 1 LASTPIN (1150 4525) BN 1
J 2
(1202 4533);
DISPLAY 0.617021 (1202 4533);
PAINT VIOLET (1202 4533);
FORCEPROP 2 LAST BOM_COST SB
J 0
(1175 4575);
DISPLAY 0.744681 (1175 4575);
PAINT MONO (1175 4575);
DISPLAY INVISIBLE (1175 4575);
FORCEPROP 2 LAST CDS_LIB mstr_standard
J 0
(1200 4525);
PAINT ORANGE (1200 4525);
DISPLAY INVISIBLE (1200 4525);
FORCEPROP 1 LAST BODY_TYPE PLUMBING
J 2
(1200 4475);
DISPLAY 0.872340 (1200 4475);
PAINT GREEN (1200 4475);
DISPLAY INVISIBLE (1200 4475);
FORCEPROP 1 LAST HDL_TAP TRUE
J 2
(875 4400);
DISPLAY 0.872340 (875 4400);
PAINT GREEN (875 4400);
DISPLAY INVISIBLE (875 4400);
FORCEPROP 1 LAST PATH I4
J 2
(1202 4525);
DISPLAY 0.872340 (1202 4525);
PAINT GREEN (1202 4525);
DISPLAY INVISIBLE (1202 4525);
FORCEADD TAP..1
R 2
(-150 3575);
FORCEPROP 3 LASTPIN (-100 3575) SIG_NAME DMI_CPU0_PCH_RX_DN<1>
J 0
(-90 3585);
DISPLAY 0.659574 (-90 3585);
PAINT MONO (-90 3585);
DISPLAY INVISIBLE (-90 3585);
FORCEPROP 1 LASTPIN (-100 3575) BN 1
J 2
(-88 3583);
DISPLAY 0.617021 (-88 3583);
PAINT VIOLET (-88 3583);
FORCEPROP 2 LAST BOM_COST SB
J 0
(-175 3625);
DISPLAY 0.744681 (-175 3625);
PAINT MONO (-175 3625);
DISPLAY INVISIBLE (-175 3625);
FORCEPROP 2 LAST CDS_LIB mstr_standard
J 0
(-150 3575);
PAINT ORANGE (-150 3575);
DISPLAY INVISIBLE (-150 3575);
FORCEPROP 1 LAST BODY_TYPE PLUMBING
J 2
(-150 3625);
DISPLAY 1.085106 (-150 3625);
PAINT GREEN (-150 3625);
DISPLAY INVISIBLE (-150 3625);
FORCEPROP 1 LAST HDL_TAP TRUE
J 2
(-475 3450);
DISPLAY 1.085106 (-475 3450);
PAINT GREEN (-475 3450);
DISPLAY INVISIBLE (-475 3450);
FORCEPROP 1 LAST PATH I40
J 2
(-148 3575);
DISPLAY 0.872340 (-148 3575);
PAINT GREEN (-148 3575);
DISPLAY INVISIBLE (-148 3575);
FORCEADD OFFPAGE..1
(-1000 4075);
FORCEPROP 2 LAST $XR0 117 
J 0
(-1282 4075);
DISPLAY 0.638298 (-1282 4075);
PAINT MONO (-1282 4075);
FORCEPROP 2 LAST BOM_COST SB
J 0
(-1275 4125);
DISPLAY 0.744681 (-1275 4125);
PAINT MONO (-1275 4125);
DISPLAY INVISIBLE (-1275 4125);
FORCEPROP 2 LAST CDS_LIB mstr_standard
J 0
(-1000 4075);
PAINT ORANGE (-1000 4075);
DISPLAY INVISIBLE (-1000 4075);
FORCEPROP 1 LAST OFFPAGE TRUE
J 0
(-675 3950);
DISPLAY 1.085106 (-675 3950);
PAINT GREEN (-675 3950);
DISPLAY INVISIBLE (-675 3950);
FORCEPROP 1 LAST COMMENT_BODY TRUE
J 0
(-875 3975);
DISPLAY 1.085106 (-875 3975);
PAINT PEACH (-875 3975);
DISPLAY INVISIBLE (-875 3975);
FORCEPROP 2 LAST PATH I42
J 0
(-1250 4150);
DISPLAY 1.021277 (-1250 4150);
PAINT ORANGE (-1250 4150);
DISPLAY INVISIBLE (-1250 4150);
FORCEADD OFFPAGE..2
(-1900 4075);
FORCEPROP 2 LAST $XR0 29 
J 0
(-1711 4075);
DISPLAY 0.638298 (-1711 4075);
PAINT MONO (-1711 4075);
FORCEPROP 2 LAST BOM_COST SB
J 0
(-1600 4125);
DISPLAY 0.744681 (-1600 4125);
PAINT MONO (-1600 4125);
DISPLAY INVISIBLE (-1600 4125);
FORCEPROP 2 LAST CDS_LIB mstr_standard
J 0
(-1900 4075);
PAINT ORANGE (-1900 4075);
DISPLAY INVISIBLE (-1900 4075);
FORCEPROP 1 LAST OFFPAGE TRUE
J 0
(-1575 3950);
DISPLAY 0.872340 (-1575 3950);
PAINT GREEN (-1575 3950);
DISPLAY INVISIBLE (-1575 3950);
FORCEPROP 1 LAST COMMENT_BODY TRUE
J 0
(-1945 3980);
DISPLAY 0.872340 (-1945 3980);
PAINT PEACH (-1945 3980);
DISPLAY INVISIBLE (-1945 3980);
FORCEPROP 2 LAST PATH I43
J 0
(-1600 4150);
DISPLAY 1.021277 (-1600 4150);
PAINT ORANGE (-1600 4150);
DISPLAY INVISIBLE (-1600 4150);
FORCEADD TAP..6
R 2
(-2800 3975);
FORCEPROP 3 LASTPIN (-2850 3975) SIG_NAME DMI_CPU0_PCH_RX_C_DP<3>
J 0
(-2840 3985);
DISPLAY 0.659574 (-2840 3985);
PAINT MONO (-2840 3985);
DISPLAY INVISIBLE (-2840 3985);
FORCEPROP 1 LASTPIN (-2850 3975) BN 3
J 2
(-2798 3983);
DISPLAY 0.617021 (-2798 3983);
PAINT VIOLET (-2798 3983);
FORCEPROP 2 LAST BOM_COST SB
J 0
(-2825 4025);
DISPLAY 0.744681 (-2825 4025);
PAINT MONO (-2825 4025);
DISPLAY INVISIBLE (-2825 4025);
FORCEPROP 2 LAST CDS_LIB mstr_standard
J 0
(-2800 3975);
PAINT ORANGE (-2800 3975);
DISPLAY INVISIBLE (-2800 3975);
FORCEPROP 1 LAST BODY_TYPE PLUMBING
J 2
(-2800 3925);
DISPLAY 0.872340 (-2800 3925);
PAINT GREEN (-2800 3925);
DISPLAY INVISIBLE (-2800 3925);
FORCEPROP 1 LAST HDL_TAP TRUE
J 2
(-3125 3850);
DISPLAY 0.872340 (-3125 3850);
PAINT RED (-3125 3850);
DISPLAY INVISIBLE (-3125 3850);
FORCEPROP 1 LAST PATH I45
J 2
(-2798 3975);
DISPLAY 0.872340 (-2798 3975);
PAINT GREEN (-2798 3975);
DISPLAY INVISIBLE (-2798 3975);
FORCEADD TAP..6
R 2
(-2800 3775);
FORCEPROP 3 LASTPIN (-2850 3775) SIG_NAME DMI_CPU0_PCH_RX_C_DP<2>
J 0
(-2840 3785);
DISPLAY 0.659574 (-2840 3785);
PAINT MONO (-2840 3785);
DISPLAY INVISIBLE (-2840 3785);
FORCEPROP 1 LASTPIN (-2850 3775) BN 2
J 2
(-2798 3783);
DISPLAY 0.617021 (-2798 3783);
PAINT VIOLET (-2798 3783);
FORCEPROP 2 LAST BOM_COST SB
J 0
(-2825 3825);
DISPLAY 0.744681 (-2825 3825);
PAINT MONO (-2825 3825);
DISPLAY INVISIBLE (-2825 3825);
FORCEPROP 2 LAST CDS_LIB mstr_standard
J 0
(-2800 3775);
PAINT ORANGE (-2800 3775);
DISPLAY INVISIBLE (-2800 3775);
FORCEPROP 1 LAST BODY_TYPE PLUMBING
J 2
(-2800 3725);
DISPLAY 0.872340 (-2800 3725);
PAINT GREEN (-2800 3725);
DISPLAY INVISIBLE (-2800 3725);
FORCEPROP 1 LAST HDL_TAP TRUE
J 2
(-3125 3650);
DISPLAY 0.872340 (-3125 3650);
PAINT RED (-3125 3650);
DISPLAY INVISIBLE (-3125 3650);
FORCEPROP 1 LAST PATH I46
J 2
(-2798 3775);
DISPLAY 0.872340 (-2798 3775);
PAINT GREEN (-2798 3775);
DISPLAY INVISIBLE (-2798 3775);
FORCEADD TAP..6
R 2
(-2800 3375);
FORCEPROP 3 LASTPIN (-2850 3375) SIG_NAME DMI_CPU0_PCH_RX_C_DP<0>
J 0
(-2840 3385);
DISPLAY 0.659574 (-2840 3385);
PAINT MONO (-2840 3385);
DISPLAY INVISIBLE (-2840 3385);
FORCEPROP 1 LASTPIN (-2850 3375) BN 0
J 2
(-2798 3383);
DISPLAY 0.617021 (-2798 3383);
PAINT VIOLET (-2798 3383);
FORCEPROP 2 LAST BOM_COST SB
J 0
(-2825 3425);
DISPLAY 0.744681 (-2825 3425);
PAINT MONO (-2825 3425);
DISPLAY INVISIBLE (-2825 3425);
FORCEPROP 2 LAST CDS_LIB mstr_standard
J 0
(-2800 3375);
PAINT ORANGE (-2800 3375);
DISPLAY INVISIBLE (-2800 3375);
FORCEPROP 1 LAST BODY_TYPE PLUMBING
J 2
(-2800 3325);
DISPLAY 0.872340 (-2800 3325);
PAINT GREEN (-2800 3325);
DISPLAY INVISIBLE (-2800 3325);
FORCEPROP 1 LAST HDL_TAP TRUE
J 2
(-3125 3250);
DISPLAY 0.872340 (-3125 3250);
PAINT RED (-3125 3250);
DISPLAY INVISIBLE (-3125 3250);
FORCEPROP 1 LAST PATH I47
J 2
(-2798 3375);
DISPLAY 0.872340 (-2798 3375);
PAINT GREEN (-2798 3375);
DISPLAY INVISIBLE (-2798 3375);
FORCEADD TAP..6
R 2
(-2800 3575);
FORCEPROP 3 LASTPIN (-2850 3575) SIG_NAME DMI_CPU0_PCH_RX_C_DP<1>
J 0
(-2840 3585);
DISPLAY 0.659574 (-2840 3585);
PAINT MONO (-2840 3585);
DISPLAY INVISIBLE (-2840 3585);
FORCEPROP 1 LASTPIN (-2850 3575) BN 1
J 2
(-2798 3583);
DISPLAY 0.617021 (-2798 3583);
PAINT VIOLET (-2798 3583);
FORCEPROP 2 LAST BOM_COST SB
J 0
(-2825 3625);
DISPLAY 0.744681 (-2825 3625);
PAINT MONO (-2825 3625);
DISPLAY INVISIBLE (-2825 3625);
FORCEPROP 2 LAST CDS_LIB mstr_standard
J 0
(-2800 3575);
PAINT ORANGE (-2800 3575);
DISPLAY INVISIBLE (-2800 3575);
FORCEPROP 1 LAST BODY_TYPE PLUMBING
J 2
(-2800 3525);
DISPLAY 0.872340 (-2800 3525);
PAINT GREEN (-2800 3525);
DISPLAY INVISIBLE (-2800 3525);
FORCEPROP 1 LAST HDL_TAP TRUE
J 2
(-3125 3450);
DISPLAY 0.872340 (-3125 3450);
PAINT RED (-3125 3450);
DISPLAY INVISIBLE (-3125 3450);
FORCEPROP 1 LAST PATH I48
J 2
(-2798 3575);
DISPLAY 0.872340 (-2798 3575);
PAINT GREEN (-2798 3575);
DISPLAY INVISIBLE (-2798 3575);
FORCEADD TAP..6
R 2
(1200 4325);
FORCEPROP 3 LASTPIN (1150 4325) SIG_NAME DMI_CPU0_PCH_TX_C_DN<0>
J 0
(1160 4335);
DISPLAY 0.659574 (1160 4335);
PAINT MONO (1160 4335);
DISPLAY INVISIBLE (1160 4335);
FORCEPROP 1 LASTPIN (1150 4325) BN 0
J 2
(1202 4333);
DISPLAY 0.617021 (1202 4333);
PAINT VIOLET (1202 4333);
FORCEPROP 2 LAST BOM_COST SB
J 0
(1175 4375);
DISPLAY 0.744681 (1175 4375);
PAINT MONO (1175 4375);
DISPLAY INVISIBLE (1175 4375);
FORCEPROP 2 LAST CDS_LIB mstr_standard
J 0
(1200 4325);
PAINT ORANGE (1200 4325);
DISPLAY INVISIBLE (1200 4325);
FORCEPROP 1 LAST BODY_TYPE PLUMBING
J 2
(1200 4275);
DISPLAY 0.872340 (1200 4275);
PAINT GREEN (1200 4275);
DISPLAY INVISIBLE (1200 4275);
FORCEPROP 1 LAST HDL_TAP TRUE
J 2
(875 4200);
DISPLAY 0.872340 (875 4200);
PAINT GREEN (875 4200);
DISPLAY INVISIBLE (875 4200);
FORCEPROP 1 LAST PATH I5
J 2
(1202 4325);
DISPLAY 0.872340 (1202 4325);
PAINT GREEN (1202 4325);
DISPLAY INVISIBLE (1202 4325);
FORCEADD TAP..1
R 2
(-4150 4925);
FORCEPROP 3 LASTPIN (-4100 4925) SIG_NAME DMI_CPU0_PCH_TX_DP<3>
J 0
(-4090 4935);
DISPLAY 0.659574 (-4090 4935);
PAINT MONO (-4090 4935);
DISPLAY INVISIBLE (-4090 4935);
FORCEPROP 1 LASTPIN (-4100 4925) BN 3
J 2
(-4088 4933);
DISPLAY 0.617021 (-4088 4933);
PAINT VIOLET (-4088 4933);
FORCEPROP 2 LAST BOM_COST SB
J 0
(-4175 4975);
DISPLAY 0.744681 (-4175 4975);
PAINT MONO (-4175 4975);
DISPLAY INVISIBLE (-4175 4975);
FORCEPROP 2 LAST CDS_LIB mstr_standard
J 0
(-4150 4925);
PAINT ORANGE (-4150 4925);
DISPLAY INVISIBLE (-4150 4925);
FORCEPROP 1 LAST BODY_TYPE PLUMBING
J 2
(-4150 4975);
DISPLAY 1.085106 (-4150 4975);
PAINT GREEN (-4150 4975);
DISPLAY INVISIBLE (-4150 4975);
FORCEPROP 1 LAST HDL_TAP TRUE
J 2
(-4475 4800);
DISPLAY 1.085106 (-4475 4800);
PAINT GREEN (-4475 4800);
DISPLAY INVISIBLE (-4475 4800);
FORCEPROP 1 LAST PATH I57
J 2
(-4148 4925);
DISPLAY 0.872340 (-4148 4925);
PAINT GREEN (-4148 4925);
DISPLAY INVISIBLE (-4148 4925);
FORCEADD TAP..1
R 2
(-4150 4725);
FORCEPROP 3 LASTPIN (-4100 4725) SIG_NAME DMI_CPU0_PCH_TX_DP<2>
J 0
(-4090 4735);
DISPLAY 0.659574 (-4090 4735);
PAINT MONO (-4090 4735);
DISPLAY INVISIBLE (-4090 4735);
FORCEPROP 1 LASTPIN (-4100 4725) BN 2
J 2
(-4088 4733);
DISPLAY 0.617021 (-4088 4733);
PAINT VIOLET (-4088 4733);
FORCEPROP 2 LAST BOM_COST SB
J 0
(-4175 4775);
DISPLAY 0.744681 (-4175 4775);
PAINT MONO (-4175 4775);
DISPLAY INVISIBLE (-4175 4775);
FORCEPROP 2 LAST CDS_LIB mstr_standard
J 0
(-4150 4725);
PAINT ORANGE (-4150 4725);
DISPLAY INVISIBLE (-4150 4725);
FORCEPROP 1 LAST BODY_TYPE PLUMBING
J 2
(-4150 4775);
DISPLAY 1.085106 (-4150 4775);
PAINT GREEN (-4150 4775);
DISPLAY INVISIBLE (-4150 4775);
FORCEPROP 1 LAST HDL_TAP TRUE
J 2
(-4475 4600);
DISPLAY 1.085106 (-4475 4600);
PAINT GREEN (-4475 4600);
DISPLAY INVISIBLE (-4475 4600);
FORCEPROP 1 LAST PATH I58
J 2
(-4148 4725);
DISPLAY 0.872340 (-4148 4725);
PAINT GREEN (-4148 4725);
DISPLAY INVISIBLE (-4148 4725);
FORCEADD TAP..1
R 2
(-4150 4525);
FORCEPROP 3 LASTPIN (-4100 4525) SIG_NAME DMI_CPU0_PCH_TX_DP<1>
J 0
(-4090 4535);
DISPLAY 0.659574 (-4090 4535);
PAINT MONO (-4090 4535);
DISPLAY INVISIBLE (-4090 4535);
FORCEPROP 1 LASTPIN (-4100 4525) BN 1
J 2
(-4088 4533);
DISPLAY 0.617021 (-4088 4533);
PAINT VIOLET (-4088 4533);
FORCEPROP 2 LAST BOM_COST SB
J 0
(-4175 4575);
DISPLAY 0.744681 (-4175 4575);
PAINT MONO (-4175 4575);
DISPLAY INVISIBLE (-4175 4575);
FORCEPROP 2 LAST CDS_LIB mstr_standard
J 0
(-4150 4525);
PAINT ORANGE (-4150 4525);
DISPLAY INVISIBLE (-4150 4525);
FORCEPROP 1 LAST BODY_TYPE PLUMBING
J 2
(-4150 4575);
DISPLAY 1.085106 (-4150 4575);
PAINT GREEN (-4150 4575);
DISPLAY INVISIBLE (-4150 4575);
FORCEPROP 1 LAST HDL_TAP TRUE
J 2
(-4475 4400);
DISPLAY 1.085106 (-4475 4400);
PAINT GREEN (-4475 4400);
DISPLAY INVISIBLE (-4475 4400);
FORCEPROP 1 LAST PATH I59
J 2
(-4148 4525);
DISPLAY 0.872340 (-4148 4525);
PAINT GREEN (-4148 4525);
DISPLAY INVISIBLE (-4148 4525);
FORCEADD TAP..1
R 2
(-4150 4325);
FORCEPROP 3 LASTPIN (-4100 4325) SIG_NAME DMI_CPU0_PCH_TX_DP<0>
J 0
(-4090 4335);
DISPLAY 0.659574 (-4090 4335);
PAINT MONO (-4090 4335);
DISPLAY INVISIBLE (-4090 4335);
FORCEPROP 1 LASTPIN (-4100 4325) BN 0
J 2
(-4088 4333);
DISPLAY 0.617021 (-4088 4333);
PAINT VIOLET (-4088 4333);
FORCEPROP 2 LAST BOM_COST SB
J 0
(-4175 4375);
DISPLAY 0.744681 (-4175 4375);
PAINT MONO (-4175 4375);
DISPLAY INVISIBLE (-4175 4375);
FORCEPROP 2 LAST CDS_LIB mstr_standard
J 0
(-4150 4325);
PAINT ORANGE (-4150 4325);
DISPLAY INVISIBLE (-4150 4325);
FORCEPROP 1 LAST BODY_TYPE PLUMBING
J 2
(-4150 4375);
DISPLAY 1.085106 (-4150 4375);
PAINT GREEN (-4150 4375);
DISPLAY INVISIBLE (-4150 4375);
FORCEPROP 1 LAST HDL_TAP TRUE
J 2
(-4475 4200);
DISPLAY 1.085106 (-4475 4200);
PAINT GREEN (-4475 4200);
DISPLAY INVISIBLE (-4475 4200);
FORCEPROP 1 LAST PATH I60
J 2
(-4148 4325);
DISPLAY 0.872340 (-4148 4325);
PAINT GREEN (-4148 4325);
DISPLAY INVISIBLE (-4148 4325);
FORCEADD OFFPAGE..1
(-5050 5025);
FORCEPROP 2 LAST $XR0 29 
J 0
(-5301 5025);
DISPLAY 0.638298 (-5301 5025);
PAINT MONO (-5301 5025);
FORCEPROP 2 LAST BOM_COST SB
J 0
(-5300 5075);
DISPLAY 0.744681 (-5300 5075);
PAINT MONO (-5300 5075);
DISPLAY INVISIBLE (-5300 5075);
FORCEPROP 2 LAST CDS_LIB mstr_standard
J 0
(-5050 5025);
PAINT ORANGE (-5050 5025);
DISPLAY INVISIBLE (-5050 5025);
FORCEPROP 1 LAST OFFPAGE TRUE
J 0
(-4725 4900);
DISPLAY 1.085106 (-4725 4900);
PAINT GREEN (-4725 4900);
DISPLAY INVISIBLE (-4725 4900);
FORCEPROP 1 LAST COMMENT_BODY TRUE
J 0
(-4925 4925);
DISPLAY 1.085106 (-4925 4925);
PAINT PEACH (-4925 4925);
DISPLAY INVISIBLE (-4925 4925);
FORCEPROP 2 LAST PATH I61
J 0
(-5300 5100);
DISPLAY 1.021277 (-5300 5100);
PAINT ORANGE (-5300 5100);
DISPLAY INVISIBLE (-5300 5100);
FORCEADD TAP..1
R 2
(-4150 3975);
FORCEPROP 3 LASTPIN (-4100 3975) SIG_NAME DMI_CPU0_PCH_RX_DP<3>
J 0
(-4090 3985);
DISPLAY 0.659574 (-4090 3985);
PAINT MONO (-4090 3985);
DISPLAY INVISIBLE (-4090 3985);
FORCEPROP 1 LASTPIN (-4100 3975) BN 3
J 2
(-4088 3983);
DISPLAY 0.617021 (-4088 3983);
PAINT VIOLET (-4088 3983);
FORCEPROP 2 LAST BOM_COST SB
J 0
(-4175 4025);
DISPLAY 0.744681 (-4175 4025);
PAINT MONO (-4175 4025);
DISPLAY INVISIBLE (-4175 4025);
FORCEPROP 2 LAST CDS_LIB mstr_standard
J 0
(-4150 3975);
PAINT ORANGE (-4150 3975);
DISPLAY INVISIBLE (-4150 3975);
FORCEPROP 1 LAST BODY_TYPE PLUMBING
J 2
(-4150 4025);
DISPLAY 1.085106 (-4150 4025);
PAINT GREEN (-4150 4025);
DISPLAY INVISIBLE (-4150 4025);
FORCEPROP 1 LAST HDL_TAP TRUE
J 2
(-4475 3850);
DISPLAY 1.085106 (-4475 3850);
PAINT GREEN (-4475 3850);
DISPLAY INVISIBLE (-4475 3850);
FORCEPROP 1 LAST PATH I62
J 2
(-4148 3975);
DISPLAY 0.872340 (-4148 3975);
PAINT GREEN (-4148 3975);
DISPLAY INVISIBLE (-4148 3975);
FORCEADD TAP..1
R 2
(-4150 3775);
FORCEPROP 3 LASTPIN (-4100 3775) SIG_NAME DMI_CPU0_PCH_RX_DP<2>
J 0
(-4090 3785);
DISPLAY 0.659574 (-4090 3785);
PAINT MONO (-4090 3785);
DISPLAY INVISIBLE (-4090 3785);
FORCEPROP 1 LASTPIN (-4100 3775) BN 2
J 2
(-4088 3783);
DISPLAY 0.617021 (-4088 3783);
PAINT VIOLET (-4088 3783);
FORCEPROP 2 LAST BOM_COST SB
J 0
(-4175 3825);
DISPLAY 0.744681 (-4175 3825);
PAINT MONO (-4175 3825);
DISPLAY INVISIBLE (-4175 3825);
FORCEPROP 2 LAST CDS_LIB mstr_standard
J 0
(-4150 3775);
PAINT ORANGE (-4150 3775);
DISPLAY INVISIBLE (-4150 3775);
FORCEPROP 1 LAST BODY_TYPE PLUMBING
J 2
(-4150 3825);
DISPLAY 1.085106 (-4150 3825);
PAINT GREEN (-4150 3825);
DISPLAY INVISIBLE (-4150 3825);
FORCEPROP 1 LAST HDL_TAP TRUE
J 2
(-4475 3650);
DISPLAY 1.085106 (-4475 3650);
PAINT GREEN (-4475 3650);
DISPLAY INVISIBLE (-4475 3650);
FORCEPROP 1 LAST PATH I63
J 2
(-4148 3775);
DISPLAY 0.872340 (-4148 3775);
PAINT GREEN (-4148 3775);
DISPLAY INVISIBLE (-4148 3775);
FORCEADD TAP..1
R 2
(-4150 3375);
FORCEPROP 3 LASTPIN (-4100 3375) SIG_NAME DMI_CPU0_PCH_RX_DP<0>
J 0
(-4090 3385);
DISPLAY 0.659574 (-4090 3385);
PAINT MONO (-4090 3385);
DISPLAY INVISIBLE (-4090 3385);
FORCEPROP 1 LASTPIN (-4100 3375) BN 0
J 2
(-4088 3383);
DISPLAY 0.617021 (-4088 3383);
PAINT VIOLET (-4088 3383);
FORCEPROP 2 LAST BOM_COST SB
J 0
(-4175 3425);
DISPLAY 0.744681 (-4175 3425);
PAINT MONO (-4175 3425);
DISPLAY INVISIBLE (-4175 3425);
FORCEPROP 2 LAST CDS_LIB mstr_standard
J 0
(-4150 3375);
PAINT ORANGE (-4150 3375);
DISPLAY INVISIBLE (-4150 3375);
FORCEPROP 1 LAST BODY_TYPE PLUMBING
J 2
(-4150 3425);
DISPLAY 1.085106 (-4150 3425);
PAINT GREEN (-4150 3425);
DISPLAY INVISIBLE (-4150 3425);
FORCEPROP 1 LAST HDL_TAP TRUE
J 2
(-4475 3250);
DISPLAY 1.085106 (-4475 3250);
PAINT GREEN (-4475 3250);
DISPLAY INVISIBLE (-4475 3250);
FORCEPROP 1 LAST PATH I64
J 2
(-4148 3375);
DISPLAY 0.872340 (-4148 3375);
PAINT GREEN (-4148 3375);
DISPLAY INVISIBLE (-4148 3375);
FORCEADD TAP..1
R 2
(-4150 3575);
FORCEPROP 3 LASTPIN (-4100 3575) SIG_NAME DMI_CPU0_PCH_RX_DP<1>
J 0
(-4090 3585);
DISPLAY 0.659574 (-4090 3585);
PAINT MONO (-4090 3585);
DISPLAY INVISIBLE (-4090 3585);
FORCEPROP 1 LASTPIN (-4100 3575) BN 1
J 2
(-4088 3583);
DISPLAY 0.617021 (-4088 3583);
PAINT VIOLET (-4088 3583);
FORCEPROP 2 LAST BOM_COST SB
J 0
(-4175 3625);
DISPLAY 0.744681 (-4175 3625);
PAINT MONO (-4175 3625);
DISPLAY INVISIBLE (-4175 3625);
FORCEPROP 2 LAST CDS_LIB mstr_standard
J 0
(-4150 3575);
PAINT ORANGE (-4150 3575);
DISPLAY INVISIBLE (-4150 3575);
FORCEPROP 1 LAST BODY_TYPE PLUMBING
J 2
(-4150 3625);
DISPLAY 1.085106 (-4150 3625);
PAINT GREEN (-4150 3625);
DISPLAY INVISIBLE (-4150 3625);
FORCEPROP 1 LAST HDL_TAP TRUE
J 2
(-4475 3450);
DISPLAY 1.085106 (-4475 3450);
PAINT GREEN (-4475 3450);
DISPLAY INVISIBLE (-4475 3450);
FORCEPROP 1 LAST PATH I65
J 2
(-4148 3575);
DISPLAY 0.872340 (-4148 3575);
PAINT GREEN (-4148 3575);
DISPLAY INVISIBLE (-4148 3575);
FORCEADD OFFPAGE..1
(-5050 4075);
FORCEPROP 2 LAST $XR0 117 
J 0
(-5302 4075);
DISPLAY 0.638298 (-5302 4075);
PAINT MONO (-5302 4075);
FORCEPROP 2 LAST BOM_COST SB
J 0
(-5300 4125);
DISPLAY 0.744681 (-5300 4125);
PAINT MONO (-5300 4125);
DISPLAY INVISIBLE (-5300 4125);
FORCEPROP 2 LAST CDS_LIB mstr_standard
J 0
(-5050 4075);
PAINT ORANGE (-5050 4075);
DISPLAY INVISIBLE (-5050 4075);
FORCEPROP 1 LAST OFFPAGE TRUE
J 0
(-4725 3950);
DISPLAY 1.085106 (-4725 3950);
PAINT GREEN (-4725 3950);
DISPLAY INVISIBLE (-4725 3950);
FORCEPROP 1 LAST COMMENT_BODY TRUE
J 0
(-4925 3975);
DISPLAY 1.085106 (-4925 3975);
PAINT PEACH (-4925 3975);
DISPLAY INVISIBLE (-4925 3975);
FORCEPROP 2 LAST PATH I67
J 0
(-5300 4150);
DISPLAY 1.021277 (-5300 4150);
PAINT ORANGE (-5300 4150);
DISPLAY INVISIBLE (-5300 4150);
FORCEADD CAP..1
R 1
(-3300 4725);
FORCEPROP 1 LAST VALUE 0.22UF
J 0
(-3500 4675);
DISPLAY 0.617021 (-3500 4675);
PAINT SKYBLUE (-3500 4675);
FORCEPROP 1 LAST TOLERANCE 10%
J 0
(-3475 4625);
DISPLAY 0.617021 (-3475 4625);
PAINT SKYBLUE (-3475 4625);
FORCEPROP 1 LASTPIN (-3400 4725) $PN 1
J 0
(-3405 4735);
DISPLAY 0.617021 (-3405 4735);
PAINT WHITE (-3405 4735);
FORCEPROP 1 LAST LOCATION C7B27
J 0
(-3375 4825);
DISPLAY 0.617021 (-3375 4825);
PAINT AQUA (-3375 4825);
FORCEPROP 1 LAST PART_NUMBER A36096-155
J 0
(-3450 4775);
DISPLAY 0.617021 (-3450 4775);
PAINT BLUE (-3450 4775);
FORCEPROP 1 LASTPIN (-3200 4725) $PN 2
J 0
(-3230 4735);
DISPLAY 0.617021 (-3230 4735);
PAINT WHITE (-3230 4735);
FORCEPROP 1 LAST VOLTAGE 16V
J 0
(-3250 4675);
DISPLAY 0.638298 (-3250 4675);
PAINT SKYBLUE (-3250 4675);
FORCEPROP 1 LAST MATERIAL X7R
J 0
(-3250 4625);
DISPLAY 0.617021 (-3250 4625);
PAINT SKYBLUE (-3250 4625);
FORCEPROP 1 LAST PACK_TYPE 0402
J 0
(-3475 4575);
DISPLAY 0.617021 (-3475 4575);
PAINT SKYBLUE (-3475 4575);
FORCEPROP 2 LAST BOM_COST SB
J 0
(-3375 4875);
DISPLAY 0.744681 (-3375 4875);
PAINT MONO (-3375 4875);
DISPLAY INVISIBLE (-3375 4875);
FORCEPROP 2 LAST CDS_LIB mstr_discrete
J 0
(-3300 4725);
PAINT ORANGE (-3300 4725);
DISPLAY INVISIBLE (-3300 4725);
FORCEPROP 2 LAST CDS_SEC 1
J 0
(-3175 5025);
PAINT MONO (-3175 5025);
DISPLAY INVISIBLE (-3175 5025);
FORCEPROP 2 LAST $SEC 1
J 0
(-3175 5025);
PAINT MONO (-3175 5025);
DISPLAY INVISIBLE (-3175 5025);
FORCEPROP 2 LAST CDS_LOCATION C7B27
J 0
(-3375 4825);
DISPLAY 0.617021 (-3375 4825);
PAINT AQUA (-3375 4825);
DISPLAY INVISIBLE (-3375 4825);
FORCEPROP 1 LAST PATH I69
R 1
J 0
(-3450 4775);
DISPLAY 0.978723 (-3450 4775);
PAINT WHITE (-3450 4775);
DISPLAY INVISIBLE (-3450 4775);
FORCEPROP 2 LAST ROOM DMI
J 0
(-3175 5025);
PAINT ORANGE (-3175 5025);
DISPLAY INVISIBLE (-3175 5025);
FORCEADD CAP..1
R 1
(-3650 4525);
FORCEPROP 1 LAST VALUE 0.22UF
J 0
(-3850 4475);
DISPLAY 0.617021 (-3850 4475);
PAINT SKYBLUE (-3850 4475);
FORCEPROP 1 LAST TOLERANCE 10%
J 0
(-3825 4425);
DISPLAY 0.617021 (-3825 4425);
PAINT SKYBLUE (-3825 4425);
FORCEPROP 1 LASTPIN (-3550 4525) $PN 2
J 0
(-3580 4535);
DISPLAY 0.617021 (-3580 4535);
PAINT WHITE (-3580 4535);
FORCEPROP 1 LASTPIN (-3750 4525) $PN 1
J 0
(-3755 4535);
DISPLAY 0.617021 (-3755 4535);
PAINT WHITE (-3755 4535);
FORCEPROP 1 LAST VOLTAGE 16V
J 0
(-3600 4475);
DISPLAY 0.638298 (-3600 4475);
PAINT SKYBLUE (-3600 4475);
FORCEPROP 1 LAST MATERIAL X7R
J 0
(-3600 4425);
DISPLAY 0.617021 (-3600 4425);
PAINT SKYBLUE (-3600 4425);
FORCEPROP 1 LAST PACK_TYPE 0402
J 0
(-3825 4375);
DISPLAY 0.617021 (-3825 4375);
PAINT SKYBLUE (-3825 4375);
FORCEPROP 1 LAST PART_NUMBER A36096-155
J 0
(-3800 4575);
DISPLAY 0.617021 (-3800 4575);
PAINT BLUE (-3800 4575);
FORCEPROP 1 LAST LOCATION C7B28
J 0
(-3725 4625);
DISPLAY 0.617021 (-3725 4625);
PAINT AQUA (-3725 4625);
FORCEPROP 2 LAST BOM_COST SB
J 0
(-3725 4675);
DISPLAY 0.744681 (-3725 4675);
PAINT MONO (-3725 4675);
DISPLAY INVISIBLE (-3725 4675);
FORCEPROP 2 LAST CDS_LIB mstr_discrete
J 0
(-3650 4525);
PAINT ORANGE (-3650 4525);
DISPLAY INVISIBLE (-3650 4525);
FORCEPROP 2 LAST CDS_SEC 1
J 0
(-3525 4825);
PAINT MONO (-3525 4825);
DISPLAY INVISIBLE (-3525 4825);
FORCEPROP 2 LAST $SEC 1
J 0
(-3525 4825);
PAINT MONO (-3525 4825);
DISPLAY INVISIBLE (-3525 4825);
FORCEPROP 2 LAST CDS_LOCATION C7B28
J 0
(-3725 4625);
DISPLAY 0.617021 (-3725 4625);
PAINT AQUA (-3725 4625);
DISPLAY INVISIBLE (-3725 4625);
FORCEPROP 1 LAST PATH I70
R 1
J 0
(-3800 4575);
DISPLAY 0.978723 (-3800 4575);
PAINT WHITE (-3800 4575);
DISPLAY INVISIBLE (-3800 4575);
FORCEPROP 2 LAST ROOM DMI
J 0
(-3525 4825);
PAINT ORANGE (-3525 4825);
DISPLAY INVISIBLE (-3525 4825);
FORCEADD CAP..1
R 1
(-3300 4325);
FORCEPROP 1 LAST VALUE 0.22UF
J 0
(-3500 4275);
DISPLAY 0.617021 (-3500 4275);
PAINT SKYBLUE (-3500 4275);
FORCEPROP 1 LASTPIN (-3200 4325) $PN 2
J 0
(-3230 4335);
DISPLAY 0.617021 (-3230 4335);
PAINT WHITE (-3230 4335);
FORCEPROP 1 LASTPIN (-3400 4325) $PN 1
J 0
(-3405 4335);
DISPLAY 0.617021 (-3405 4335);
PAINT WHITE (-3405 4335);
FORCEPROP 1 LAST LOCATION C7C2
J 0
(-3375 4425);
DISPLAY 0.617021 (-3375 4425);
PAINT AQUA (-3375 4425);
FORCEPROP 1 LAST PART_NUMBER A36096-155
J 0
(-3450 4375);
DISPLAY 0.617021 (-3450 4375);
PAINT BLUE (-3450 4375);
FORCEPROP 1 LAST VOLTAGE 16V
J 0
(-3250 4275);
DISPLAY 0.638298 (-3250 4275);
PAINT SKYBLUE (-3250 4275);
FORCEPROP 1 LAST MATERIAL X7R
J 0
(-3250 4225);
DISPLAY 0.617021 (-3250 4225);
PAINT SKYBLUE (-3250 4225);
FORCEPROP 1 LAST TOLERANCE 10%
J 0
(-3475 4225);
DISPLAY 0.617021 (-3475 4225);
PAINT SKYBLUE (-3475 4225);
FORCEPROP 1 LAST PACK_TYPE 0402
J 0
(-3475 4175);
DISPLAY 0.617021 (-3475 4175);
PAINT SKYBLUE (-3475 4175);
FORCEPROP 2 LAST BOM_COST SB
J 0
(-3375 4475);
DISPLAY 0.744681 (-3375 4475);
PAINT MONO (-3375 4475);
DISPLAY INVISIBLE (-3375 4475);
FORCEPROP 2 LAST CDS_LIB mstr_discrete
J 0
(-3300 4325);
PAINT ORANGE (-3300 4325);
DISPLAY INVISIBLE (-3300 4325);
FORCEPROP 2 LAST CDS_SEC 1
J 0
(-3175 4625);
PAINT MONO (-3175 4625);
DISPLAY INVISIBLE (-3175 4625);
FORCEPROP 2 LAST $SEC 1
J 0
(-3175 4625);
PAINT MONO (-3175 4625);
DISPLAY INVISIBLE (-3175 4625);
FORCEPROP 2 LAST CDS_LOCATION C7C2
J 0
(-3375 4425);
DISPLAY 0.617021 (-3375 4425);
PAINT AQUA (-3375 4425);
DISPLAY INVISIBLE (-3375 4425);
FORCEPROP 1 LAST PATH I71
R 1
J 0
(-3450 4375);
DISPLAY 0.978723 (-3450 4375);
PAINT WHITE (-3450 4375);
DISPLAY INVISIBLE (-3450 4375);
FORCEPROP 2 LAST ROOM DMI
J 0
(-3175 4625);
PAINT ORANGE (-3175 4625);
DISPLAY INVISIBLE (-3175 4625);
FORCEADD CAP..1
R 1
(-3300 3375);
FORCEPROP 1 LAST LOCATION C3M40
J 0
(-3375 3475);
DISPLAY 0.617021 (-3375 3475);
PAINT AQUA (-3375 3475);
FORCEPROP 1 LAST VALUE 0.22UF
J 0
(-3500 3325);
DISPLAY 0.617021 (-3500 3325);
PAINT SKYBLUE (-3500 3325);
FORCEPROP 1 LAST TOLERANCE 10%
J 0
(-3475 3275);
DISPLAY 0.617021 (-3475 3275);
PAINT SKYBLUE (-3475 3275);
FORCEPROP 1 LAST MATERIAL X7R
J 0
(-3250 3275);
DISPLAY 0.617021 (-3250 3275);
PAINT SKYBLUE (-3250 3275);
FORCEPROP 1 LASTPIN (-3200 3375) $PN 2
J 0
(-3230 3385);
DISPLAY 0.617021 (-3230 3385);
PAINT WHITE (-3230 3385);
FORCEPROP 1 LASTPIN (-3400 3375) $PN 1
J 0
(-3405 3385);
DISPLAY 0.617021 (-3405 3385);
PAINT WHITE (-3405 3385);
FORCEPROP 1 LAST PACK_TYPE 0402
J 0
(-3475 3225);
DISPLAY 0.617021 (-3475 3225);
PAINT SKYBLUE (-3475 3225);
FORCEPROP 1 LAST VOLTAGE 16V
J 0
(-3250 3325);
DISPLAY 0.638298 (-3250 3325);
PAINT SKYBLUE (-3250 3325);
FORCEPROP 1 LAST PART_NUMBER A36096-155
J 0
(-3450 3425);
DISPLAY 0.617021 (-3450 3425);
PAINT BLUE (-3450 3425);
FORCEPROP 2 LAST CDS_LIB mstr_discrete
J 0
(-3300 3375);
PAINT ORANGE (-3300 3375);
DISPLAY INVISIBLE (-3300 3375);
FORCEPROP 2 LAST BOM_COST SB
J 0
(-3375 3525);
DISPLAY 0.744681 (-3375 3525);
PAINT MONO (-3375 3525);
DISPLAY INVISIBLE (-3375 3525);
FORCEPROP 2 LAST CDS_SEC 1
J 0
(-3175 3675);
PAINT MONO (-3175 3675);
DISPLAY INVISIBLE (-3175 3675);
FORCEPROP 2 LAST $SEC 1
J 0
(-3175 3675);
PAINT MONO (-3175 3675);
DISPLAY INVISIBLE (-3175 3675);
FORCEPROP 2 LAST CDS_LOCATION C3M40
J 0
(-3375 3475);
DISPLAY 0.617021 (-3375 3475);
PAINT AQUA (-3375 3475);
DISPLAY INVISIBLE (-3375 3475);
FORCEPROP 1 LAST PATH I72
R 1
J 0
(-3450 3425);
DISPLAY 0.978723 (-3450 3425);
PAINT WHITE (-3450 3425);
DISPLAY INVISIBLE (-3450 3425);
FORCEPROP 2 LAST ROOM DMI
J 0
(-3175 3675);
PAINT ORANGE (-3175 3675);
DISPLAY INVISIBLE (-3175 3675);
FORCEADD CAP..1
R 1
(-3650 3575);
FORCEPROP 1 LAST LOCATION C3M37
J 0
(-3725 3675);
DISPLAY 0.617021 (-3725 3675);
PAINT AQUA (-3725 3675);
FORCEPROP 1 LAST PART_NUMBER A36096-155
J 0
(-3800 3625);
DISPLAY 0.617021 (-3800 3625);
PAINT BLUE (-3800 3625);
FORCEPROP 1 LAST VALUE 0.22UF
J 0
(-3850 3525);
DISPLAY 0.617021 (-3850 3525);
PAINT SKYBLUE (-3850 3525);
FORCEPROP 1 LAST TOLERANCE 10%
J 0
(-3825 3475);
DISPLAY 0.617021 (-3825 3475);
PAINT SKYBLUE (-3825 3475);
FORCEPROP 1 LAST PACK_TYPE 0402
J 0
(-3825 3425);
DISPLAY 0.617021 (-3825 3425);
PAINT SKYBLUE (-3825 3425);
FORCEPROP 1 LAST MATERIAL X7R
J 0
(-3600 3475);
DISPLAY 0.617021 (-3600 3475);
PAINT SKYBLUE (-3600 3475);
FORCEPROP 1 LASTPIN (-3550 3575) $PN 2
J 0
(-3580 3585);
DISPLAY 0.617021 (-3580 3585);
PAINT WHITE (-3580 3585);
FORCEPROP 1 LASTPIN (-3750 3575) $PN 1
J 0
(-3755 3585);
DISPLAY 0.617021 (-3755 3585);
PAINT WHITE (-3755 3585);
FORCEPROP 1 LAST VOLTAGE 16V
J 0
(-3600 3525);
DISPLAY 0.638298 (-3600 3525);
PAINT SKYBLUE (-3600 3525);
FORCEPROP 2 LAST CDS_LIB mstr_discrete
J 0
(-3650 3575);
PAINT ORANGE (-3650 3575);
DISPLAY INVISIBLE (-3650 3575);
FORCEPROP 2 LAST BOM_COST SB
J 0
(-3725 3725);
DISPLAY 0.744681 (-3725 3725);
PAINT MONO (-3725 3725);
DISPLAY INVISIBLE (-3725 3725);
FORCEPROP 2 LAST CDS_SEC 1
J 0
(-3525 3875);
PAINT MONO (-3525 3875);
DISPLAY INVISIBLE (-3525 3875);
FORCEPROP 2 LAST $SEC 1
J 0
(-3525 3875);
PAINT MONO (-3525 3875);
DISPLAY INVISIBLE (-3525 3875);
FORCEPROP 2 LAST CDS_LOCATION C3M37
J 0
(-3725 3675);
DISPLAY 0.617021 (-3725 3675);
PAINT AQUA (-3725 3675);
DISPLAY INVISIBLE (-3725 3675);
FORCEPROP 1 LAST PATH I73
R 1
J 0
(-3800 3625);
DISPLAY 0.978723 (-3800 3625);
PAINT WHITE (-3800 3625);
DISPLAY INVISIBLE (-3800 3625);
FORCEPROP 2 LAST ROOM DMI
J 0
(-3525 3875);
PAINT ORANGE (-3525 3875);
DISPLAY INVISIBLE (-3525 3875);
FORCEADD CAP..1
R 1
(-3300 3775);
FORCEPROP 1 LAST LOCATION C3N9
J 0
(-3375 3875);
DISPLAY 0.617021 (-3375 3875);
PAINT AQUA (-3375 3875);
FORCEPROP 1 LAST VALUE 0.22UF
J 0
(-3500 3725);
DISPLAY 0.617021 (-3500 3725);
PAINT SKYBLUE (-3500 3725);
FORCEPROP 1 LAST TOLERANCE 10%
J 0
(-3475 3675);
DISPLAY 0.617021 (-3475 3675);
PAINT SKYBLUE (-3475 3675);
FORCEPROP 1 LAST PACK_TYPE 0402
J 0
(-3475 3625);
DISPLAY 0.617021 (-3475 3625);
PAINT SKYBLUE (-3475 3625);
FORCEPROP 1 LAST MATERIAL X7R
J 0
(-3250 3675);
DISPLAY 0.617021 (-3250 3675);
PAINT SKYBLUE (-3250 3675);
FORCEPROP 1 LASTPIN (-3200 3775) $PN 2
J 0
(-3230 3785);
DISPLAY 0.617021 (-3230 3785);
PAINT WHITE (-3230 3785);
FORCEPROP 1 LASTPIN (-3400 3775) $PN 1
J 0
(-3405 3785);
DISPLAY 0.617021 (-3405 3785);
PAINT WHITE (-3405 3785);
FORCEPROP 1 LAST PART_NUMBER A36096-155
J 0
(-3450 3825);
DISPLAY 0.617021 (-3450 3825);
PAINT BLUE (-3450 3825);
FORCEPROP 1 LAST VOLTAGE 16V
J 0
(-3250 3725);
DISPLAY 0.638298 (-3250 3725);
PAINT SKYBLUE (-3250 3725);
FORCEPROP 2 LAST CDS_LIB mstr_discrete
J 0
(-3300 3775);
PAINT ORANGE (-3300 3775);
DISPLAY INVISIBLE (-3300 3775);
FORCEPROP 2 LAST BOM_COST SB
J 0
(-3375 3925);
DISPLAY 0.744681 (-3375 3925);
PAINT MONO (-3375 3925);
DISPLAY INVISIBLE (-3375 3925);
FORCEPROP 2 LAST CDS_SEC 1
J 0
(-3175 4075);
PAINT MONO (-3175 4075);
DISPLAY INVISIBLE (-3175 4075);
FORCEPROP 2 LAST $SEC 1
J 0
(-3175 4075);
PAINT MONO (-3175 4075);
DISPLAY INVISIBLE (-3175 4075);
FORCEPROP 2 LAST CDS_LOCATION C3N9
J 0
(-3375 3875);
DISPLAY 0.617021 (-3375 3875);
PAINT AQUA (-3375 3875);
DISPLAY INVISIBLE (-3375 3875);
FORCEPROP 1 LAST PATH I74
R 1
J 0
(-3450 3825);
DISPLAY 0.978723 (-3450 3825);
PAINT WHITE (-3450 3825);
DISPLAY INVISIBLE (-3450 3825);
FORCEPROP 2 LAST ROOM DMI
J 0
(-3175 4075);
PAINT ORANGE (-3175 4075);
DISPLAY INVISIBLE (-3175 4075);
FORCEADD CAP..1
R 1
(-3650 3975);
FORCEPROP 1 LAST VALUE 0.22UF
J 0
(-3850 3925);
DISPLAY 0.617021 (-3850 3925);
PAINT SKYBLUE (-3850 3925);
FORCEPROP 1 LAST TOLERANCE 10%
J 0
(-3825 3875);
DISPLAY 0.617021 (-3825 3875);
PAINT SKYBLUE (-3825 3875);
FORCEPROP 1 LAST PACK_TYPE 0402
J 0
(-3825 3825);
DISPLAY 0.617021 (-3825 3825);
PAINT SKYBLUE (-3825 3825);
FORCEPROP 1 LAST MATERIAL X7R
J 0
(-3600 3875);
DISPLAY 0.617021 (-3600 3875);
PAINT SKYBLUE (-3600 3875);
FORCEPROP 1 LASTPIN (-3550 3975) $PN 2
J 0
(-3580 3985);
DISPLAY 0.617021 (-3580 3985);
PAINT WHITE (-3580 3985);
FORCEPROP 1 LASTPIN (-3750 3975) $PN 1
J 0
(-3755 3985);
DISPLAY 0.617021 (-3755 3985);
PAINT WHITE (-3755 3985);
FORCEPROP 1 LAST LOCATION C3N8
J 0
(-3725 4075);
DISPLAY 0.617021 (-3725 4075);
PAINT AQUA (-3725 4075);
FORCEPROP 1 LAST VOLTAGE 16V
J 0
(-3600 3925);
DISPLAY 0.638298 (-3600 3925);
PAINT SKYBLUE (-3600 3925);
FORCEPROP 1 LAST PART_NUMBER A36096-155
J 0
(-3800 4025);
DISPLAY 0.617021 (-3800 4025);
PAINT BLUE (-3800 4025);
FORCEPROP 2 LAST CDS_LIB mstr_discrete
J 0
(-3650 3975);
PAINT ORANGE (-3650 3975);
DISPLAY INVISIBLE (-3650 3975);
FORCEPROP 2 LAST BOM_COST SB
J 0
(-3725 4125);
DISPLAY 0.744681 (-3725 4125);
PAINT MONO (-3725 4125);
DISPLAY INVISIBLE (-3725 4125);
FORCEPROP 2 LAST CDS_SEC 1
J 0
(-3525 4275);
PAINT MONO (-3525 4275);
DISPLAY INVISIBLE (-3525 4275);
FORCEPROP 2 LAST $SEC 1
J 0
(-3525 4275);
PAINT MONO (-3525 4275);
DISPLAY INVISIBLE (-3525 4275);
FORCEPROP 2 LAST CDS_LOCATION C3N8
J 0
(-3725 4075);
DISPLAY 0.617021 (-3725 4075);
PAINT AQUA (-3725 4075);
DISPLAY INVISIBLE (-3725 4075);
FORCEPROP 1 LAST PATH I75
R 1
J 0
(-3800 4025);
DISPLAY 0.978723 (-3800 4025);
PAINT WHITE (-3800 4025);
DISPLAY INVISIBLE (-3800 4025);
FORCEPROP 2 LAST ROOM DMI
J 0
(-3525 4275);
PAINT ORANGE (-3525 4275);
DISPLAY INVISIBLE (-3525 4275);
FORCEADD CAP..1
R 1
(750 4325);
FORCEPROP 1 LAST LOCATION C7C3
J 0
(675 4425);
DISPLAY 0.617021 (675 4425);
PAINT AQUA (675 4425);
FORCEPROP 1 LASTPIN (650 4325) $PN 1
J 0
(645 4335);
DISPLAY 0.617021 (645 4335);
PAINT WHITE (645 4335);
FORCEPROP 1 LAST PART_NUMBER A36096-155
J 0
(600 4375);
DISPLAY 0.617021 (600 4375);
PAINT BLUE (600 4375);
FORCEPROP 1 LASTPIN (850 4325) $PN 2
J 0
(820 4335);
DISPLAY 0.617021 (820 4335);
PAINT WHITE (820 4335);
FORCEPROP 1 LAST PACK_TYPE 0402
J 0
(575 4175);
DISPLAY 0.617021 (575 4175);
PAINT SKYBLUE (575 4175);
FORCEPROP 1 LAST TOLERANCE 10%
J 0
(575 4225);
DISPLAY 0.617021 (575 4225);
PAINT SKYBLUE (575 4225);
FORCEPROP 1 LAST VALUE 0.22UF
J 0
(550 4275);
DISPLAY 0.617021 (550 4275);
PAINT SKYBLUE (550 4275);
FORCEPROP 1 LAST MATERIAL X7R
J 0
(800 4225);
DISPLAY 0.617021 (800 4225);
PAINT SKYBLUE (800 4225);
FORCEPROP 1 LAST VOLTAGE 16V
J 0
(800 4275);
DISPLAY 0.638298 (800 4275);
PAINT SKYBLUE (800 4275);
FORCEPROP 2 LAST CDS_LIB mstr_discrete
J 0
(750 4325);
PAINT ORANGE (750 4325);
DISPLAY INVISIBLE (750 4325);
FORCEPROP 2 LAST BOM_COST SB
J 0
(675 4475);
DISPLAY 0.744681 (675 4475);
PAINT MONO (675 4475);
DISPLAY INVISIBLE (675 4475);
FORCEPROP 2 LAST CDS_SEC 1
J 0
(875 4625);
PAINT MONO (875 4625);
DISPLAY INVISIBLE (875 4625);
FORCEPROP 2 LAST $SEC 1
J 0
(875 4625);
PAINT MONO (875 4625);
DISPLAY INVISIBLE (875 4625);
FORCEPROP 2 LAST CDS_LOCATION C7C3
J 0
(675 4425);
DISPLAY 0.617021 (675 4425);
PAINT AQUA (675 4425);
DISPLAY INVISIBLE (675 4425);
FORCEPROP 1 LAST PATH I76
R 1
J 0
(600 4375);
DISPLAY 0.978723 (600 4375);
PAINT WHITE (600 4375);
DISPLAY INVISIBLE (600 4375);
FORCEPROP 2 LAST ROOM DMI
J 0
(875 4625);
PAINT ORANGE (875 4625);
DISPLAY INVISIBLE (875 4625);
FORCEADD CAP..1
R 1
(400 4525);
FORCEPROP 1 LAST MATERIAL X7R
J 0
(450 4425);
DISPLAY 0.617021 (450 4425);
PAINT SKYBLUE (450 4425);
FORCEPROP 1 LASTPIN (500 4525) $PN 2
J 0
(470 4535);
DISPLAY 0.617021 (470 4535);
PAINT WHITE (470 4535);
FORCEPROP 1 LASTPIN (300 4525) $PN 1
J 0
(295 4535);
DISPLAY 0.617021 (295 4535);
PAINT WHITE (295 4535);
FORCEPROP 1 LAST PACK_TYPE 0402
J 0
(225 4375);
DISPLAY 0.617021 (225 4375);
PAINT SKYBLUE (225 4375);
FORCEPROP 1 LAST TOLERANCE 10%
J 0
(225 4425);
DISPLAY 0.617021 (225 4425);
PAINT SKYBLUE (225 4425);
FORCEPROP 1 LAST VALUE 0.22UF
J 0
(200 4475);
DISPLAY 0.617021 (200 4475);
PAINT SKYBLUE (200 4475);
FORCEPROP 1 LAST LOCATION C7C1
J 0
(325 4625);
DISPLAY 0.617021 (325 4625);
PAINT AQUA (325 4625);
FORCEPROP 1 LAST PART_NUMBER A36096-155
J 0
(250 4575);
DISPLAY 0.617021 (250 4575);
PAINT BLUE (250 4575);
FORCEPROP 1 LAST VOLTAGE 16V
J 0
(450 4475);
DISPLAY 0.638298 (450 4475);
PAINT SKYBLUE (450 4475);
FORCEPROP 2 LAST CDS_LIB mstr_discrete
J 0
(400 4525);
PAINT ORANGE (400 4525);
DISPLAY INVISIBLE (400 4525);
FORCEPROP 2 LAST BOM_COST SB
J 0
(325 4675);
DISPLAY 0.744681 (325 4675);
PAINT MONO (325 4675);
DISPLAY INVISIBLE (325 4675);
FORCEPROP 2 LAST CDS_SEC 1
J 0
(525 4825);
PAINT MONO (525 4825);
DISPLAY INVISIBLE (525 4825);
FORCEPROP 2 LAST $SEC 1
J 0
(525 4825);
PAINT MONO (525 4825);
DISPLAY INVISIBLE (525 4825);
FORCEPROP 2 LAST CDS_LOCATION C7C1
J 0
(325 4625);
DISPLAY 0.617021 (325 4625);
PAINT AQUA (325 4625);
DISPLAY INVISIBLE (325 4625);
FORCEPROP 1 LAST PATH I77
R 1
J 0
(250 4575);
DISPLAY 0.978723 (250 4575);
PAINT WHITE (250 4575);
DISPLAY INVISIBLE (250 4575);
FORCEPROP 2 LAST ROOM DMI
J 0
(525 4825);
PAINT ORANGE (525 4825);
DISPLAY INVISIBLE (525 4825);
FORCEADD CAP..1
R 1
(750 4725);
FORCEPROP 1 LAST TOLERANCE 10%
J 0
(575 4625);
DISPLAY 0.617021 (575 4625);
PAINT SKYBLUE (575 4625);
FORCEPROP 1 LASTPIN (850 4725) $PN 2
J 0
(820 4735);
DISPLAY 0.617021 (820 4735);
PAINT WHITE (820 4735);
FORCEPROP 1 LASTPIN (650 4725) $PN 1
J 0
(645 4735);
DISPLAY 0.617021 (645 4735);
PAINT WHITE (645 4735);
FORCEPROP 1 LAST VALUE 0.22UF
J 0
(550 4675);
DISPLAY 0.617021 (550 4675);
PAINT SKYBLUE (550 4675);
FORCEPROP 1 LAST PART_NUMBER A36096-155
J 0
(600 4775);
DISPLAY 0.617021 (600 4775);
PAINT BLUE (600 4775);
FORCEPROP 1 LAST LOCATION C7B29
J 0
(675 4825);
DISPLAY 0.617021 (675 4825);
PAINT AQUA (675 4825);
FORCEPROP 1 LAST MATERIAL X7R
J 0
(800 4625);
DISPLAY 0.617021 (800 4625);
PAINT SKYBLUE (800 4625);
FORCEPROP 1 LAST PACK_TYPE 0402
J 0
(575 4575);
DISPLAY 0.617021 (575 4575);
PAINT SKYBLUE (575 4575);
FORCEPROP 1 LAST VOLTAGE 16V
J 0
(800 4675);
DISPLAY 0.638298 (800 4675);
PAINT SKYBLUE (800 4675);
FORCEPROP 2 LAST CDS_LIB mstr_discrete
J 0
(750 4725);
PAINT ORANGE (750 4725);
DISPLAY INVISIBLE (750 4725);
FORCEPROP 2 LAST BOM_COST SB
J 0
(675 4875);
DISPLAY 0.744681 (675 4875);
PAINT MONO (675 4875);
DISPLAY INVISIBLE (675 4875);
FORCEPROP 2 LAST CDS_SEC 1
J 0
(875 5025);
PAINT MONO (875 5025);
DISPLAY INVISIBLE (875 5025);
FORCEPROP 2 LAST $SEC 1
J 0
(875 5025);
PAINT MONO (875 5025);
DISPLAY INVISIBLE (875 5025);
FORCEPROP 2 LAST CDS_LOCATION C7B29
J 0
(675 4825);
DISPLAY 0.617021 (675 4825);
PAINT AQUA (675 4825);
DISPLAY INVISIBLE (675 4825);
FORCEPROP 1 LAST PATH I78
R 1
J 0
(600 4775);
DISPLAY 0.978723 (600 4775);
PAINT WHITE (600 4775);
DISPLAY INVISIBLE (600 4775);
FORCEPROP 2 LAST ROOM DMI
J 0
(875 5025);
PAINT ORANGE (875 5025);
DISPLAY INVISIBLE (875 5025);
FORCEADD CAP..1
R 1
(400 4925);
FORCEPROP 1 LAST MATERIAL X7R
J 0
(450 4825);
DISPLAY 0.617021 (450 4825);
PAINT SKYBLUE (450 4825);
FORCEPROP 1 LASTPIN (300 4925) $PN 1
J 0
(295 4935);
DISPLAY 0.617021 (295 4935);
PAINT WHITE (295 4935);
FORCEPROP 1 LAST LOCATION C7B26
J 0
(325 5025);
DISPLAY 0.617021 (325 5025);
PAINT AQUA (325 5025);
FORCEPROP 1 LAST PACK_TYPE 0402
J 0
(225 4775);
DISPLAY 0.617021 (225 4775);
PAINT SKYBLUE (225 4775);
FORCEPROP 1 LAST TOLERANCE 10%
J 0
(225 4825);
DISPLAY 0.617021 (225 4825);
PAINT SKYBLUE (225 4825);
FORCEPROP 1 LASTPIN (500 4925) $PN 2
J 0
(470 4935);
DISPLAY 0.617021 (470 4935);
PAINT WHITE (470 4935);
FORCEPROP 1 LAST VALUE 0.22UF
J 0
(200 4875);
DISPLAY 0.617021 (200 4875);
PAINT SKYBLUE (200 4875);
FORCEPROP 1 LAST VOLTAGE 16V
J 0
(450 4875);
DISPLAY 0.638298 (450 4875);
PAINT SKYBLUE (450 4875);
FORCEPROP 1 LAST PART_NUMBER A36096-155
J 0
(250 4975);
DISPLAY 0.617021 (250 4975);
PAINT BLUE (250 4975);
FORCEPROP 2 LAST CDS_LIB mstr_discrete
J 0
(400 4925);
PAINT ORANGE (400 4925);
DISPLAY INVISIBLE (400 4925);
FORCEPROP 2 LAST BOM_COST SB
J 0
(325 5075);
DISPLAY 0.744681 (325 5075);
PAINT MONO (325 5075);
DISPLAY INVISIBLE (325 5075);
FORCEPROP 2 LAST CDS_SEC 1
J 0
(525 5225);
PAINT MONO (525 5225);
DISPLAY INVISIBLE (525 5225);
FORCEPROP 2 LAST $SEC 1
J 0
(525 5225);
PAINT MONO (525 5225);
DISPLAY INVISIBLE (525 5225);
FORCEPROP 2 LAST CDS_LOCATION C7B26
J 0
(325 5025);
DISPLAY 0.617021 (325 5025);
PAINT AQUA (325 5025);
DISPLAY INVISIBLE (325 5025);
FORCEPROP 1 LAST PATH I79
R 1
J 0
(250 4975);
DISPLAY 0.978723 (250 4975);
PAINT WHITE (250 4975);
DISPLAY INVISIBLE (250 4975);
FORCEPROP 2 LAST ROOM DMI
J 0
(525 5225);
PAINT ORANGE (525 5225);
DISPLAY INVISIBLE (525 5225);
FORCEADD CAP..1
R 1
(750 3375);
FORCEPROP 1 LAST LOCATION C3M44
J 0
(675 3475);
DISPLAY 0.617021 (675 3475);
PAINT AQUA (675 3475);
FORCEPROP 1 LAST VALUE 0.22UF
J 0
(550 3325);
DISPLAY 0.617021 (550 3325);
PAINT SKYBLUE (550 3325);
FORCEPROP 1 LAST TOLERANCE 10%
J 0
(575 3275);
DISPLAY 0.617021 (575 3275);
PAINT SKYBLUE (575 3275);
FORCEPROP 1 LAST PACK_TYPE 0402
J 0
(575 3225);
DISPLAY 0.617021 (575 3225);
PAINT SKYBLUE (575 3225);
FORCEPROP 1 LAST MATERIAL X7R
J 0
(800 3275);
DISPLAY 0.617021 (800 3275);
PAINT SKYBLUE (800 3275);
FORCEPROP 1 LASTPIN (650 3375) $PN 1
J 0
(645 3385);
DISPLAY 0.617021 (645 3385);
PAINT WHITE (645 3385);
FORCEPROP 1 LAST VOLTAGE 16V
J 0
(800 3325);
DISPLAY 0.638298 (800 3325);
PAINT SKYBLUE (800 3325);
FORCEPROP 1 LASTPIN (850 3375) $PN 2
J 0
(820 3385);
DISPLAY 0.617021 (820 3385);
PAINT WHITE (820 3385);
FORCEPROP 1 LAST PART_NUMBER A36096-155
J 0
(600 3425);
DISPLAY 0.617021 (600 3425);
PAINT BLUE (600 3425);
FORCEPROP 2 LAST CDS_LIB mstr_discrete
J 0
(750 3375);
PAINT ORANGE (750 3375);
DISPLAY INVISIBLE (750 3375);
FORCEPROP 2 LAST BOM_COST SB
J 0
(675 3525);
DISPLAY 0.744681 (675 3525);
PAINT MONO (675 3525);
DISPLAY INVISIBLE (675 3525);
FORCEPROP 2 LAST CDS_SEC 1
J 0
(875 3675);
PAINT MONO (875 3675);
DISPLAY INVISIBLE (875 3675);
FORCEPROP 2 LAST $SEC 1
J 0
(875 3675);
PAINT MONO (875 3675);
DISPLAY INVISIBLE (875 3675);
FORCEPROP 2 LAST CDS_LOCATION C3M44
J 0
(675 3475);
DISPLAY 0.617021 (675 3475);
PAINT AQUA (675 3475);
DISPLAY INVISIBLE (675 3475);
FORCEPROP 1 LAST PATH I80
R 1
J 0
(600 3425);
DISPLAY 0.978723 (600 3425);
PAINT WHITE (600 3425);
DISPLAY INVISIBLE (600 3425);
FORCEPROP 2 LAST ROOM DMI
J 0
(875 3675);
PAINT ORANGE (875 3675);
DISPLAY INVISIBLE (875 3675);
FORCEADD CAP..1
R 1
(400 3575);
FORCEPROP 1 LAST PART_NUMBER A36096-155
J 0
(250 3625);
DISPLAY 0.617021 (250 3625);
PAINT BLUE (250 3625);
FORCEPROP 1 LAST VALUE 0.22UF
J 0
(200 3525);
DISPLAY 0.617021 (200 3525);
PAINT SKYBLUE (200 3525);
FORCEPROP 1 LAST TOLERANCE 10%
J 0
(225 3475);
DISPLAY 0.617021 (225 3475);
PAINT SKYBLUE (225 3475);
FORCEPROP 1 LAST PACK_TYPE 0402
J 0
(225 3425);
DISPLAY 0.617021 (225 3425);
PAINT SKYBLUE (225 3425);
FORCEPROP 1 LAST MATERIAL X7R
J 0
(450 3475);
DISPLAY 0.617021 (450 3475);
PAINT SKYBLUE (450 3475);
FORCEPROP 1 LASTPIN (500 3575) $PN 2
J 0
(470 3585);
DISPLAY 0.617021 (470 3585);
PAINT WHITE (470 3585);
FORCEPROP 1 LASTPIN (300 3575) $PN 1
J 0
(295 3585);
DISPLAY 0.617021 (295 3585);
PAINT WHITE (295 3585);
FORCEPROP 1 LAST VOLTAGE 16V
J 0
(450 3525);
DISPLAY 0.638298 (450 3525);
PAINT SKYBLUE (450 3525);
FORCEPROP 1 LAST LOCATION C3M41
J 0
(325 3675);
DISPLAY 0.617021 (325 3675);
PAINT AQUA (325 3675);
FORCEPROP 2 LAST CDS_LIB mstr_discrete
J 0
(400 3575);
PAINT ORANGE (400 3575);
DISPLAY INVISIBLE (400 3575);
FORCEPROP 2 LAST BOM_COST SB
J 0
(325 3725);
DISPLAY 0.744681 (325 3725);
PAINT MONO (325 3725);
DISPLAY INVISIBLE (325 3725);
FORCEPROP 2 LAST CDS_SEC 1
J 0
(525 3875);
PAINT MONO (525 3875);
DISPLAY INVISIBLE (525 3875);
FORCEPROP 2 LAST $SEC 1
J 0
(525 3875);
PAINT MONO (525 3875);
DISPLAY INVISIBLE (525 3875);
FORCEPROP 2 LAST CDS_LOCATION C3M41
J 0
(325 3675);
DISPLAY 0.617021 (325 3675);
PAINT AQUA (325 3675);
DISPLAY INVISIBLE (325 3675);
FORCEPROP 1 LAST PATH I81
R 1
J 0
(250 3625);
DISPLAY 0.978723 (250 3625);
PAINT WHITE (250 3625);
DISPLAY INVISIBLE (250 3625);
FORCEPROP 2 LAST ROOM DMI
J 0
(525 3875);
PAINT ORANGE (525 3875);
DISPLAY INVISIBLE (525 3875);
FORCEADD CAP..1
R 1
(750 3775);
FORCEPROP 1 LAST LOCATION C3M45
J 0
(675 3875);
DISPLAY 0.617021 (675 3875);
PAINT AQUA (675 3875);
FORCEPROP 1 LAST VALUE 0.22UF
J 0
(550 3725);
DISPLAY 0.617021 (550 3725);
PAINT SKYBLUE (550 3725);
FORCEPROP 1 LAST TOLERANCE 10%
J 0
(575 3675);
DISPLAY 0.617021 (575 3675);
PAINT SKYBLUE (575 3675);
FORCEPROP 1 LAST PACK_TYPE 0402
J 0
(575 3625);
DISPLAY 0.617021 (575 3625);
PAINT SKYBLUE (575 3625);
FORCEPROP 1 LAST MATERIAL X7R
J 0
(800 3675);
DISPLAY 0.617021 (800 3675);
PAINT SKYBLUE (800 3675);
FORCEPROP 1 LASTPIN (850 3775) $PN 2
J 0
(820 3785);
DISPLAY 0.617021 (820 3785);
PAINT WHITE (820 3785);
FORCEPROP 1 LASTPIN (650 3775) $PN 1
J 0
(645 3785);
DISPLAY 0.617021 (645 3785);
PAINT WHITE (645 3785);
FORCEPROP 1 LAST PART_NUMBER A36096-155
J 0
(600 3825);
DISPLAY 0.617021 (600 3825);
PAINT BLUE (600 3825);
FORCEPROP 1 LAST VOLTAGE 16V
J 0
(800 3725);
DISPLAY 0.638298 (800 3725);
PAINT SKYBLUE (800 3725);
FORCEPROP 2 LAST CDS_LIB mstr_discrete
J 0
(750 3775);
PAINT ORANGE (750 3775);
DISPLAY INVISIBLE (750 3775);
FORCEPROP 2 LAST BOM_COST SB
J 0
(675 3925);
DISPLAY 0.744681 (675 3925);
PAINT MONO (675 3925);
DISPLAY INVISIBLE (675 3925);
FORCEPROP 2 LAST CDS_SEC 1
J 0
(875 4075);
PAINT MONO (875 4075);
DISPLAY INVISIBLE (875 4075);
FORCEPROP 2 LAST $SEC 1
J 0
(875 4075);
PAINT MONO (875 4075);
DISPLAY INVISIBLE (875 4075);
FORCEPROP 2 LAST CDS_LOCATION C3M45
J 0
(675 3875);
DISPLAY 0.617021 (675 3875);
PAINT AQUA (675 3875);
DISPLAY INVISIBLE (675 3875);
FORCEPROP 1 LAST PATH I82
R 1
J 0
(600 3825);
DISPLAY 0.978723 (600 3825);
PAINT WHITE (600 3825);
DISPLAY INVISIBLE (600 3825);
FORCEPROP 2 LAST ROOM DMI
J 0
(875 4075);
PAINT ORANGE (875 4075);
DISPLAY INVISIBLE (875 4075);
FORCEADD CAP..1
R 1
(400 3975);
FORCEPROP 1 LAST LOCATION C3N13
J 0
(325 4075);
DISPLAY 0.617021 (325 4075);
PAINT AQUA (325 4075);
FORCEPROP 1 LAST PART_NUMBER A36096-155
J 0
(250 4025);
DISPLAY 0.617021 (250 4025);
PAINT BLUE (250 4025);
FORCEPROP 1 LAST VALUE 0.22UF
J 0
(200 3925);
DISPLAY 0.617021 (200 3925);
PAINT SKYBLUE (200 3925);
FORCEPROP 1 LAST PACK_TYPE 0402
J 0
(225 3825);
DISPLAY 0.617021 (225 3825);
PAINT SKYBLUE (225 3825);
FORCEPROP 1 LAST MATERIAL X7R
J 0
(450 3875);
DISPLAY 0.617021 (450 3875);
PAINT SKYBLUE (450 3875);
FORCEPROP 1 LASTPIN (500 3975) $PN 2
J 0
(470 3985);
DISPLAY 0.617021 (470 3985);
PAINT WHITE (470 3985);
FORCEPROP 1 LASTPIN (300 3975) $PN 1
J 0
(295 3985);
DISPLAY 0.617021 (295 3985);
PAINT WHITE (295 3985);
FORCEPROP 1 LAST TOLERANCE 10%
J 0
(225 3875);
DISPLAY 0.617021 (225 3875);
PAINT SKYBLUE (225 3875);
FORCEPROP 1 LAST VOLTAGE 16V
J 0
(450 3925);
DISPLAY 0.638298 (450 3925);
PAINT SKYBLUE (450 3925);
FORCEPROP 2 LAST CDS_LIB mstr_discrete
J 0
(400 3975);
PAINT ORANGE (400 3975);
DISPLAY INVISIBLE (400 3975);
FORCEPROP 2 LAST BOM_COST SB
J 0
(325 4125);
DISPLAY 0.744681 (325 4125);
PAINT MONO (325 4125);
DISPLAY INVISIBLE (325 4125);
FORCEPROP 2 LAST CDS_SEC 1
J 0
(525 4275);
PAINT MONO (525 4275);
DISPLAY INVISIBLE (525 4275);
FORCEPROP 2 LAST $SEC 1
J 0
(525 4275);
PAINT MONO (525 4275);
DISPLAY INVISIBLE (525 4275);
FORCEPROP 2 LAST CDS_LOCATION C3N13
J 0
(325 4075);
DISPLAY 0.617021 (325 4075);
PAINT AQUA (325 4075);
DISPLAY INVISIBLE (325 4075);
FORCEPROP 1 LAST PATH I83
R 1
J 0
(250 4025);
DISPLAY 0.978723 (250 4025);
PAINT WHITE (250 4025);
DISPLAY INVISIBLE (250 4025);
FORCEPROP 2 LAST ROOM DMI
J 0
(525 4275);
PAINT ORANGE (525 4275);
DISPLAY INVISIBLE (525 4275);
FORCEADD INTEL_CORP_BPAGE..1
(2650 500);
FORCEPROP 1 LAST CDS_CON_LAST_MODIFIED Fri Jun 16 17:48:49 2017
J 0
(1225 825);
PAINT ORANGE (1225 825);
DISPLAY INVISIBLE (1225 825);
FORCEPROP 1 LAST CUSTOM_TXT_CDS <CURRENT_DESIGN_SHEET> OF <TOTAL_DESIGN_SHEETS>
J 0
(2150 525);
PAINT ORANGE (2150 525);
FORCEPROP 1 LAST CUSTOM_TXT_CDS <CON_LAST_MODIFIED>
J 0
(-1350 600);
PAINT ORANGE (-1350 600);
FORCEPROP 2 LAST CUSTOM_TXT_CDS <XR_PAGE_TITLE>
J 0
(-5240 5750);
DISPLAY 0.638298 (-5240 5750);
PAINT PINK (-5240 5750);
DISPLAY INVISIBLE (-5240 5750);
FORCEPROP 1 LAST SCH_TITLE DMI AC COUPLING
J 0
(-5300 550);
DISPLAY 1.212766 (-5300 550);
PAINT YELLOW (-5300 550);
FORCEPROP 2 LAST CDS_LIB mstr_symbols
J 0
(2650 500);
PAINT MONO (2650 500);
DISPLAY INVISIBLE (2650 500);
FORCEPROP 2 LAST PAGE_BORDER TRUE
J 0
(-5240 5750);
DISPLAY 0.851064 (-5240 5750);
PAINT PINK (-5240 5750);
DISPLAY INVISIBLE (-5240 5750);
FORCEPROP 1 LAST COMMENT_BODY TRUE
J 0
(2662 512);
DISPLAY 0.468085 (2662 512);
PAINT PEACH (2662 512);
DISPLAY INVISIBLE (2662 512);
FORCEPROP 2 LAST CDS_XR_PAGE_TITLE CR-129 : @BASEBOARD_FAB2_LIB.BASEBOARD_FAB2(SCH_1):PAGE129
J 0
(-5240 5750);
DISPLAY 0.638298 (-5240 5750);
PAINT PINK (-5240 5750);
DISPLAY INVISIBLE (-5240 5750);
WIRE 17 -1 (1250 4075)(2100 4075);
WIRE 17 -1 (1250 4000)(1250 4075);
FORCEPROP 2 LAST SIG_NAME DMI_CPU0_PCH_RX_C_DN<3:0>
J 0
(1340 4110);
DISPLAY 0.617021 (1340 4110);
PAINT ORANGE (1340 4110);
WIRE 17 -1 (1250 3800)(1250 4000);
WIRE 17 -1 (1250 3400)(1250 3600);
WIRE 17 -1 (1250 3600)(1250 3800);
WIRE 17 -1 (-200 3400)(-200 3600);
WIRE 17 -1 (-200 4075)(-950 4075);
FORCEPROP 2 LAST SIG_NAME DMI_CPU0_PCH_RX_DN<3:0>
J 0
(-935 4085);
DISPLAY 0.617021 (-935 4085);
PAINT ORANGE (-935 4085);
WIRE 17 -1 (-200 4000)(-200 4075);
WIRE 17 -1 (-200 3600)(-200 3800);
WIRE 17 -1 (-200 3800)(-200 4000);
WIRE 17 -1 (-4200 3400)(-4200 3600);
WIRE 17 -1 (-4200 4075)(-5000 4075);
FORCEPROP 2 LAST SIG_NAME DMI_CPU0_PCH_RX_DP<3:0>
J 0
(-4985 4085);
DISPLAY 0.617021 (-4985 4085);
PAINT ORANGE (-4985 4085);
WIRE 17 -1 (-4200 4000)(-4200 4075);
WIRE 17 -1 (-4200 3600)(-4200 3800);
WIRE 17 -1 (-4200 3800)(-4200 4000);
WIRE 17 -1 (-4200 4350)(-4200 4550);
WIRE 17 -1 (-4200 5025)(-5000 5025);
FORCEPROP 2 LAST SIG_NAME DMI_CPU0_PCH_TX_DP<3:0>
J 0
(-4985 5035);
DISPLAY 0.617021 (-4985 5035);
PAINT ORANGE (-4985 5035);
WIRE 17 -1 (-4200 4950)(-4200 5025);
WIRE 17 -1 (-4200 4550)(-4200 4750);
WIRE 17 -1 (-4200 4750)(-4200 4950);
WIRE 17 -1 (1250 4350)(1250 4550);
WIRE 17 -1 (1250 5025)(2100 5025);
WIRE 17 -1 (1250 4950)(1250 5025);
FORCEPROP 2 LAST SIG_NAME DMI_CPU0_PCH_TX_C_DN<3:0>
J 0
(1315 5060);
DISPLAY 0.617021 (1315 5060);
PAINT ORANGE (1315 5060);
WIRE 17 -1 (1250 4550)(1250 4750);
WIRE 17 -1 (1250 4750)(1250 4950);
WIRE 17 -1 (-175 5025)(-950 5025);
FORCEPROP 2 LAST SIG_NAME DMI_CPU0_PCH_TX_DN<3:0>
J 0
(-935 5035);
DISPLAY 0.617021 (-935 5035);
PAINT ORANGE (-935 5035);
WIRE 17 -1 (-175 4950)(-175 5025);
WIRE 17 -1 (-175 4750)(-175 4950);
WIRE 17 -1 (-175 4350)(-175 4550);
WIRE 17 -1 (-175 4550)(-175 4750);
WIRE 17 -1 (-2750 5025)(-1950 5025);
WIRE 17 -1 (-2750 4950)(-2750 5025);
FORCEPROP 2 LAST SIG_NAME DMI_CPU0_PCH_TX_C_DP<3:0>
J 0
(-2685 5060);
DISPLAY 0.617021 (-2685 5060);
PAINT ORANGE (-2685 5060);
WIRE 17 -1 (-2750 4750)(-2750 4950);
WIRE 17 -1 (-2750 4550)(-2750 4750);
WIRE 17 -1 (-2750 4350)(-2750 4550);
WIRE 17 -1 (-2750 3400)(-2750 3600);
WIRE 17 -1 (-2750 4075)(-1950 4075);
WIRE 17 -1 (-2750 4000)(-2750 4075);
FORCEPROP 2 LAST SIG_NAME DMI_CPU0_PCH_RX_C_DP<3:0>
J 0
(-2685 4110);
DISPLAY 0.617021 (-2685 4110);
PAINT ORANGE (-2685 4110);
WIRE 17 -1 (-2750 3600)(-2750 3800);
WIRE 17 -1 (-2750 3800)(-2750 4000);
WIRE 16 -1 (-2850 3775)(-3200 3775);
WIRE 16 -1 (-4100 4525)(-3750 4525);
WIRE 16 -1 (500 3975)(1150 3975);
WIRE 16 -1 (500 4525)(1150 4525);
WIRE 16 -1 (-75 4725)(650 4725);
WIRE 16 273 (-5250 3175)(2525 3175);
WIRE 16 -1 (-3550 3575)(-2850 3575);
WIRE 16 -1 (-3200 3375)(-2850 3375);
WIRE 16 -1 (-3550 3975)(-2850 3975);
WIRE 16 -1 (-4100 4325)(-3400 4325);
WIRE 16 -1 (-100 3775)(650 3775);
WIRE 16 -1 (850 4325)(1150 4325);
WIRE 16 -1 (-75 4325)(650 4325);
WIRE 16 -1 (-2850 4725)(-3200 4725);
WIRE 16 -1 (-3550 4925)(-2850 4925);
WIRE 16 -1 (-4100 4725)(-3400 4725);
WIRE 16 -1 (-3550 4525)(-2850 4525);
WIRE 16 -1 (-3200 4325)(-2850 4325);
WIRE 16 -1 (500 4925)(1150 4925);
WIRE 16 -1 (-75 4925)(300 4925);
WIRE 16 -1 (-75 4525)(300 4525);
WIRE 16 -1 (1150 3775)(850 3775);
WIRE 16 -1 (1150 4725)(850 4725);
WIRE 16 -1 (-4100 4925)(-3750 4925);
WIRE 16 -1 (-4100 3375)(-3400 3375);
WIRE 16 -1 (-4100 3575)(-3750 3575);
WIRE 16 -1 (-4100 3775)(-3400 3775);
WIRE 16 -1 (-4100 3975)(-3750 3975);
WIRE 16 -1 (-100 3375)(650 3375);
WIRE 16 -1 (-100 3575)(300 3575);
WIRE 16 -1 (-100 3975)(300 3975);
WIRE 16 -1 (850 3375)(1150 3375);
WIRE 16 -1 (500 3575)(1150 3575);
FORCENOTE
PLACE CAPS NEAR PCH
(-1725 3525) 0;
DISPLAY LEFT (-1725 3525);
DISPLAY 1.021277 (-1725 3525);
PAINT PURPLE (-1725 3525);
FORCENOTE
BOM_COST=SB
(-5275 3225) 0;
DISPLAY LEFT (-5275 3225);
DISPLAY 1.021277 (-5275 3225);
PAINT PURPLE (-5275 3225);
FORCENOTE
ROOM=DMI
(-5275 3300) 0;
DISPLAY LEFT (-5275 3300);
DISPLAY 1.021277 (-5275 3300);
PAINT PURPLE (-5275 3300);
FORCENOTE
CAD NOTE:
(-1725 3600) 0;
DISPLAY LEFT (-1725 3600);
DISPLAY 1.021277 (-1725 3600);
PAINT PURPLE (-1725 3600);
FORCENOTE
DMI AC CAPS
(-1800 5225) 0;
DISPLAY LEFT (-1800 5225);
DISPLAY 1.595745 (-1800 5225);
PAINT PURPLE (-1800 5225);
QUIT
